G04*
G04 #@! TF.GenerationSoftware,Altium Limited,Altium Designer,22.4.2 (48)*
G04*
G04 Layer_Physical_Order=2*
G04 Layer_Color=65280*
%FSLAX25Y25*%
%MOIN*%
G70*
G04*
G04 #@! TF.SameCoordinates,446674BB-F454-490D-8607-5140536C8ADF*
G04*
G04*
G04 #@! TF.FilePolarity,Positive*
G04*
G01*
G75*
%ADD157C,0.05906*%
%ADD159C,0.07500*%
%ADD160C,0.05000*%
%ADD161C,0.09843*%
%ADD164C,0.08661*%
%ADD167C,0.01600*%
%ADD171C,0.01968*%
G36*
X25084Y21169D02*
X25308Y20669D01*
X25068Y20309D01*
X24943Y19685D01*
X25068Y19061D01*
X25421Y18531D01*
X25951Y18178D01*
X26575Y18054D01*
X27199Y18178D01*
X27728Y18531D01*
X28082Y19061D01*
X28206Y19685D01*
X28082Y20309D01*
X27842Y20669D01*
X28066Y21169D01*
X31831D01*
X32099Y20669D01*
X31957Y20457D01*
X31833Y19833D01*
X31957Y19209D01*
X32311Y18679D01*
X32840Y18326D01*
X33465Y18202D01*
X34089Y18326D01*
X34618Y18679D01*
X34972Y19209D01*
X35096Y19833D01*
X34972Y20457D01*
X34830Y20669D01*
X35098Y21169D01*
X38863D01*
X39087Y20669D01*
X38847Y20309D01*
X38723Y19685D01*
X38847Y19061D01*
X39201Y18531D01*
X39730Y18178D01*
X40354Y18054D01*
X40979Y18178D01*
X41508Y18531D01*
X41862Y19061D01*
X41986Y19685D01*
X41862Y20309D01*
X41621Y20669D01*
X41845Y21169D01*
X45753D01*
X45977Y20669D01*
X45737Y20309D01*
X45613Y19685D01*
X45737Y19061D01*
X46091Y18531D01*
X46620Y18178D01*
X47244Y18054D01*
X47868Y18178D01*
X48398Y18531D01*
X48751Y19061D01*
X48875Y19685D01*
X48751Y20309D01*
X48511Y20669D01*
X48735Y21169D01*
X699564Y21169D01*
X699564Y-363786D01*
X283662D01*
X283193Y-363879D01*
X282796Y-364144D01*
X282531Y-364541D01*
X282438Y-365009D01*
Y-392667D01*
X201420D01*
Y-385876D01*
X201412Y-385836D01*
X201418Y-385796D01*
X201386Y-385307D01*
X201355Y-385191D01*
X201347Y-385071D01*
X201094Y-384128D01*
X201023Y-383984D01*
X200972Y-383833D01*
X200483Y-382987D01*
X200378Y-382867D01*
X200289Y-382734D01*
X199599Y-382043D01*
X199466Y-381954D01*
X199345Y-381849D01*
X198504Y-381363D01*
X197741Y-380600D01*
X194941D01*
X193862Y-381679D01*
X193568Y-381849D01*
X193448Y-381954D01*
X193315Y-382043D01*
X192624Y-382734D01*
X192535Y-382867D01*
X192430Y-382987D01*
X192260Y-383280D01*
X191741Y-383800D01*
Y-384421D01*
X191567Y-385071D01*
X191559Y-385191D01*
X191528Y-385307D01*
X191496Y-385796D01*
X191501Y-385836D01*
X191493Y-385876D01*
Y-392667D01*
X149846D01*
Y-372195D01*
X149840Y-372165D01*
X149844Y-372134D01*
X149809Y-371430D01*
X149787Y-371342D01*
Y-371252D01*
X149641Y-370515D01*
Y-368300D01*
X145041Y-363700D01*
X137841D01*
X133341Y-368200D01*
Y-369973D01*
X133087Y-371252D01*
Y-371342D01*
X133065Y-371430D01*
X133030Y-372134D01*
X133035Y-372165D01*
X133028Y-372195D01*
Y-383091D01*
X103979D01*
Y-365009D01*
X103886Y-364541D01*
X103641Y-364174D01*
Y-364000D01*
X103405D01*
X103224Y-363879D01*
X102756Y-363786D01*
X30512D01*
X30044Y-363879D01*
X29863Y-364000D01*
X29641D01*
Y-364153D01*
X29381Y-364541D01*
X29288Y-365009D01*
Y-396266D01*
X-27320D01*
Y20639D01*
X-26790Y21169D01*
X25084D01*
D02*
G37*
%LPC*%
G36*
X592808Y17690D02*
X585302D01*
Y10184D01*
X592808D01*
Y17690D01*
D02*
G37*
G36*
X579055Y17722D02*
X578076Y17593D01*
X577163Y17215D01*
X576379Y16613D01*
X575777Y15830D01*
X575399Y14917D01*
X575270Y13937D01*
X575399Y12957D01*
X575777Y12044D01*
X576379Y11260D01*
X577163Y10659D01*
X578076Y10281D01*
X579055Y10152D01*
X580035Y10281D01*
X580948Y10659D01*
X581732Y11260D01*
X582333Y12044D01*
X582711Y12957D01*
X582840Y13937D01*
X582711Y14917D01*
X582333Y15830D01*
X581732Y16613D01*
X580948Y17215D01*
X580035Y17593D01*
X579055Y17722D01*
D02*
G37*
G36*
X569055D02*
X568076Y17593D01*
X567163Y17215D01*
X566379Y16613D01*
X565777Y15830D01*
X565399Y14917D01*
X565270Y13937D01*
X565399Y12957D01*
X565777Y12044D01*
X566379Y11260D01*
X567163Y10659D01*
X568076Y10281D01*
X569055Y10152D01*
X570035Y10281D01*
X570948Y10659D01*
X571732Y11260D01*
X572333Y12044D01*
X572711Y12957D01*
X572840Y13937D01*
X572711Y14917D01*
X572333Y15830D01*
X571732Y16613D01*
X570948Y17215D01*
X570035Y17593D01*
X569055Y17722D01*
D02*
G37*
G36*
X559055D02*
X558076Y17593D01*
X557163Y17215D01*
X556379Y16613D01*
X555777Y15830D01*
X555399Y14917D01*
X555270Y13937D01*
X555399Y12957D01*
X555777Y12044D01*
X556379Y11260D01*
X557163Y10659D01*
X558076Y10281D01*
X559055Y10152D01*
X560035Y10281D01*
X560948Y10659D01*
X561732Y11260D01*
X562333Y12044D01*
X562711Y12957D01*
X562840Y13937D01*
X562711Y14917D01*
X562333Y15830D01*
X561732Y16613D01*
X560948Y17215D01*
X560035Y17593D01*
X559055Y17722D01*
D02*
G37*
G36*
X539055D02*
X538075Y17593D01*
X537163Y17215D01*
X536379Y16613D01*
X535777Y15830D01*
X535399Y14917D01*
X535270Y13937D01*
X535399Y12957D01*
X535777Y12044D01*
X536379Y11260D01*
X537163Y10659D01*
X538075Y10281D01*
X539055Y10152D01*
X540035Y10281D01*
X540948Y10659D01*
X541732Y11260D01*
X542333Y12044D01*
X542711Y12957D01*
X542840Y13937D01*
X542711Y14917D01*
X542333Y15830D01*
X541732Y16613D01*
X540948Y17215D01*
X540035Y17593D01*
X539055Y17722D01*
D02*
G37*
G36*
X589055Y7722D02*
X588075Y7593D01*
X587163Y7215D01*
X586379Y6613D01*
X585777Y5830D01*
X585399Y4917D01*
X585270Y3937D01*
X585399Y2957D01*
X585777Y2044D01*
X586379Y1261D01*
X587163Y659D01*
X588075Y281D01*
X589055Y152D01*
X590035Y281D01*
X590948Y659D01*
X591732Y1261D01*
X592333Y2044D01*
X592711Y2957D01*
X592840Y3937D01*
X592711Y4917D01*
X592333Y5830D01*
X591732Y6613D01*
X590948Y7215D01*
X590035Y7593D01*
X589055Y7722D01*
D02*
G37*
G36*
X579055D02*
X578076Y7593D01*
X577163Y7215D01*
X576379Y6613D01*
X575777Y5830D01*
X575399Y4917D01*
X575270Y3937D01*
X575399Y2957D01*
X575777Y2044D01*
X576379Y1261D01*
X577163Y659D01*
X578076Y281D01*
X579055Y152D01*
X580035Y281D01*
X580948Y659D01*
X581732Y1261D01*
X582333Y2044D01*
X582711Y2957D01*
X582840Y3937D01*
X582711Y4917D01*
X582333Y5830D01*
X581732Y6613D01*
X580948Y7215D01*
X580035Y7593D01*
X579055Y7722D01*
D02*
G37*
G36*
X569055D02*
X568076Y7593D01*
X567163Y7215D01*
X566379Y6613D01*
X565777Y5830D01*
X565399Y4917D01*
X565270Y3937D01*
X565399Y2957D01*
X565777Y2044D01*
X566379Y1261D01*
X567163Y659D01*
X568076Y281D01*
X569055Y152D01*
X570035Y281D01*
X570948Y659D01*
X571732Y1261D01*
X572333Y2044D01*
X572711Y2957D01*
X572840Y3937D01*
X572711Y4917D01*
X572333Y5830D01*
X571732Y6613D01*
X570948Y7215D01*
X570035Y7593D01*
X569055Y7722D01*
D02*
G37*
G36*
X559055D02*
X558076Y7593D01*
X557163Y7215D01*
X556379Y6613D01*
X555777Y5830D01*
X555399Y4917D01*
X555270Y3937D01*
X555399Y2957D01*
X555777Y2044D01*
X556379Y1261D01*
X557163Y659D01*
X558076Y281D01*
X559055Y152D01*
X560035Y281D01*
X560948Y659D01*
X561732Y1261D01*
X562333Y2044D01*
X562711Y2957D01*
X562840Y3937D01*
X562711Y4917D01*
X562333Y5830D01*
X561732Y6613D01*
X560948Y7215D01*
X560035Y7593D01*
X559055Y7722D01*
D02*
G37*
G36*
X539055D02*
X538075Y7593D01*
X537163Y7215D01*
X536379Y6613D01*
X535777Y5830D01*
X535399Y4917D01*
X535270Y3937D01*
X535399Y2957D01*
X535777Y2044D01*
X536379Y1261D01*
X537163Y659D01*
X538075Y281D01*
X539055Y152D01*
X540035Y281D01*
X540948Y659D01*
X541732Y1261D01*
X542333Y2044D01*
X542711Y2957D01*
X542840Y3937D01*
X542711Y4917D01*
X542333Y5830D01*
X541732Y6613D01*
X540948Y7215D01*
X540035Y7593D01*
X539055Y7722D01*
D02*
G37*
G36*
X310069Y18245D02*
X308374Y18112D01*
X306721Y17715D01*
X305151Y17064D01*
X303701Y16176D01*
X302409Y15072D01*
X301305Y13780D01*
X300416Y12330D01*
X299766Y10759D01*
X299369Y9106D01*
X299236Y7412D01*
X299369Y5717D01*
X299766Y4064D01*
X300416Y2493D01*
X301305Y1044D01*
X302409Y-249D01*
X303701Y-1353D01*
X305151Y-2241D01*
X306721Y-2891D01*
X308374Y-3288D01*
X310069Y-3422D01*
X311764Y-3288D01*
X313417Y-2891D01*
X314987Y-2241D01*
X316437Y-1353D01*
X317729Y-249D01*
X318833Y1044D01*
X319722Y2493D01*
X320372Y4064D01*
X320769Y5717D01*
X320902Y7412D01*
X320769Y9106D01*
X320372Y10759D01*
X319722Y12330D01*
X318833Y13780D01*
X317729Y15072D01*
X316437Y16176D01*
X314987Y17064D01*
X313417Y17715D01*
X311764Y18112D01*
X310069Y18245D01*
D02*
G37*
G36*
X71880D02*
X70185Y18112D01*
X68532Y17715D01*
X66962Y17064D01*
X65512Y16176D01*
X64220Y15072D01*
X63116Y13780D01*
X62227Y12330D01*
X61577Y10759D01*
X61180Y9106D01*
X61046Y7412D01*
X61180Y5717D01*
X61577Y4064D01*
X62227Y2493D01*
X63116Y1044D01*
X64220Y-249D01*
X65512Y-1353D01*
X66962Y-2241D01*
X68532Y-2891D01*
X70185Y-3288D01*
X71880Y-3422D01*
X73575Y-3288D01*
X75228Y-2891D01*
X76798Y-2241D01*
X78248Y-1353D01*
X79540Y-249D01*
X80644Y1044D01*
X81533Y2493D01*
X82183Y4064D01*
X82580Y5717D01*
X82713Y7412D01*
X82580Y9106D01*
X82183Y10759D01*
X81533Y12330D01*
X80644Y13780D01*
X79540Y15072D01*
X78248Y16176D01*
X76798Y17064D01*
X75228Y17715D01*
X73575Y18112D01*
X71880Y18245D01*
D02*
G37*
G36*
X651545Y18088D02*
X649851Y17954D01*
X648198Y17558D01*
X646627Y16907D01*
X645178Y16019D01*
X643885Y14915D01*
X642781Y13622D01*
X641893Y12173D01*
X641242Y10602D01*
X640845Y8949D01*
X640712Y7254D01*
X640845Y5560D01*
X641242Y3907D01*
X641893Y2336D01*
X642781Y887D01*
X643885Y-406D01*
X645178Y-1510D01*
X646627Y-2398D01*
X648198Y-3049D01*
X649851Y-3446D01*
X651545Y-3579D01*
X653240Y-3446D01*
X654893Y-3049D01*
X656463Y-2398D01*
X657913Y-1510D01*
X659206Y-406D01*
X660310Y887D01*
X661198Y2336D01*
X661848Y3907D01*
X662245Y5560D01*
X662379Y7254D01*
X662245Y8949D01*
X661848Y10602D01*
X661198Y12173D01*
X660310Y13622D01*
X659206Y14915D01*
X657913Y16019D01*
X656463Y16907D01*
X654893Y17558D01*
X653240Y17954D01*
X651545Y18088D01*
D02*
G37*
G36*
X413356D02*
X411662Y17954D01*
X410009Y17558D01*
X408438Y16907D01*
X406989Y16019D01*
X405696Y14915D01*
X404592Y13622D01*
X403704Y12173D01*
X403053Y10602D01*
X402656Y8949D01*
X402523Y7254D01*
X402656Y5560D01*
X403053Y3907D01*
X403704Y2336D01*
X404592Y887D01*
X405696Y-406D01*
X406989Y-1510D01*
X408438Y-2398D01*
X410009Y-3049D01*
X411662Y-3446D01*
X413356Y-3579D01*
X415051Y-3446D01*
X416704Y-3049D01*
X418274Y-2398D01*
X419724Y-1510D01*
X421017Y-406D01*
X422121Y887D01*
X423009Y2336D01*
X423660Y3907D01*
X424056Y5560D01*
X424190Y7254D01*
X424056Y8949D01*
X423660Y10602D01*
X423009Y12173D01*
X422121Y13622D01*
X421017Y14915D01*
X419724Y16019D01*
X418274Y16907D01*
X416704Y17558D01*
X415051Y17954D01*
X413356Y18088D01*
D02*
G37*
G36*
X615158Y-7227D02*
X614533Y-7351D01*
X614004Y-7705D01*
X613650Y-8234D01*
X613526Y-8858D01*
X613650Y-9483D01*
X614004Y-10012D01*
X614533Y-10365D01*
X615158Y-10490D01*
X615782Y-10365D01*
X616311Y-10012D01*
X616665Y-9483D01*
X616789Y-8858D01*
X616665Y-8234D01*
X616311Y-7705D01*
X615782Y-7351D01*
X615158Y-7227D01*
D02*
G37*
G36*
X47244D02*
X46620Y-7351D01*
X46091Y-7705D01*
X45737Y-8234D01*
X45613Y-8858D01*
X45737Y-9483D01*
X46091Y-10012D01*
X46620Y-10365D01*
X47244Y-10490D01*
X47868Y-10365D01*
X48398Y-10012D01*
X48751Y-9483D01*
X48875Y-8858D01*
X48751Y-8234D01*
X48398Y-7705D01*
X47868Y-7351D01*
X47244Y-7227D01*
D02*
G37*
G36*
X40354D02*
X39730Y-7351D01*
X39201Y-7705D01*
X38847Y-8234D01*
X38723Y-8858D01*
X38847Y-9483D01*
X39201Y-10012D01*
X39730Y-10365D01*
X40354Y-10490D01*
X40979Y-10365D01*
X41508Y-10012D01*
X41862Y-9483D01*
X41986Y-8858D01*
X41862Y-8234D01*
X41508Y-7705D01*
X40979Y-7351D01*
X40354Y-7227D01*
D02*
G37*
G36*
X33465D02*
X32840Y-7351D01*
X32311Y-7705D01*
X31957Y-8234D01*
X31833Y-8858D01*
X31957Y-9483D01*
X32311Y-10012D01*
X32840Y-10365D01*
X33465Y-10490D01*
X34089Y-10365D01*
X34618Y-10012D01*
X34972Y-9483D01*
X35096Y-8858D01*
X34972Y-8234D01*
X34618Y-7705D01*
X34089Y-7351D01*
X33465Y-7227D01*
D02*
G37*
G36*
X26495Y-7360D02*
X25871Y-7484D01*
X25342Y-7838D01*
X24988Y-8367D01*
X24864Y-8991D01*
X24988Y-9616D01*
X25342Y-10145D01*
X25871Y-10498D01*
X26495Y-10623D01*
X27120Y-10498D01*
X27649Y-10145D01*
X28002Y-9616D01*
X28127Y-8991D01*
X28002Y-8367D01*
X27649Y-7838D01*
X27120Y-7484D01*
X26495Y-7360D01*
D02*
G37*
G36*
X685039Y13341D02*
X682952Y13177D01*
X680917Y12688D01*
X678983Y11887D01*
X677198Y10793D01*
X675606Y9434D01*
X674246Y7842D01*
X673152Y6057D01*
X672351Y4123D01*
X671863Y2087D01*
X671698Y0D01*
X671863Y-2087D01*
X672351Y-4123D01*
X673152Y-6057D01*
X674246Y-7842D01*
X675606Y-9434D01*
X677198Y-10793D01*
X678983Y-11887D01*
X680917Y-12688D01*
X682952Y-13177D01*
X685039Y-13341D01*
X687126Y-13177D01*
X689162Y-12688D01*
X691096Y-11887D01*
X692881Y-10793D01*
X694473Y-9434D01*
X695833Y-7842D01*
X696926Y-6057D01*
X697728Y-4123D01*
X698216Y-2087D01*
X698381Y0D01*
X698216Y2087D01*
X697728Y4123D01*
X696926Y6057D01*
X695833Y7842D01*
X694473Y9434D01*
X692881Y10793D01*
X691096Y11887D01*
X689162Y12688D01*
X687126Y13177D01*
X685039Y13341D01*
D02*
G37*
G36*
X0D02*
X-2087Y13177D01*
X-4123Y12688D01*
X-6057Y11887D01*
X-7842Y10793D01*
X-9434Y9434D01*
X-10793Y7842D01*
X-11887Y6057D01*
X-12688Y4123D01*
X-13177Y2087D01*
X-13341Y0D01*
X-13177Y-2087D01*
X-12688Y-4123D01*
X-11887Y-6057D01*
X-10793Y-7842D01*
X-9434Y-9434D01*
X-7842Y-10793D01*
X-6057Y-11887D01*
X-4123Y-12688D01*
X-2087Y-13177D01*
X0Y-13341D01*
X2087Y-13177D01*
X4123Y-12688D01*
X6057Y-11887D01*
X7842Y-10793D01*
X9434Y-9434D01*
X10793Y-7842D01*
X11887Y-6057D01*
X12688Y-4123D01*
X13177Y-2087D01*
X13341Y0D01*
X13177Y2087D01*
X12688Y4123D01*
X11887Y6057D01*
X10793Y7842D01*
X9434Y9434D01*
X7842Y10793D01*
X6057Y11887D01*
X4123Y12688D01*
X2087Y13177D01*
X0Y13341D01*
D02*
G37*
G36*
X640640Y-15621D02*
X639744Y-15799D01*
X638984Y-16307D01*
X638477Y-17066D01*
X638299Y-17962D01*
X638477Y-18858D01*
X638984Y-19618D01*
X639744Y-20125D01*
X640640Y-20303D01*
X641536Y-20125D01*
X642295Y-19618D01*
X642803Y-18858D01*
X642981Y-17962D01*
X642803Y-17066D01*
X642295Y-16307D01*
X641536Y-15799D01*
X640640Y-15621D01*
D02*
G37*
G36*
X658465Y-20268D02*
X657840Y-20392D01*
X657311Y-20746D01*
X656957Y-21275D01*
X656833Y-21899D01*
X656957Y-22524D01*
X657311Y-23053D01*
X657840Y-23406D01*
X658465Y-23531D01*
X659089Y-23406D01*
X659618Y-23053D01*
X659972Y-22524D01*
X660096Y-21899D01*
X659972Y-21275D01*
X659618Y-20746D01*
X659089Y-20392D01*
X658465Y-20268D01*
D02*
G37*
G36*
X625000D02*
X624376Y-20392D01*
X623846Y-20746D01*
X623493Y-21275D01*
X623369Y-21899D01*
X623493Y-22524D01*
X623846Y-23053D01*
X624376Y-23406D01*
X625000Y-23531D01*
X625624Y-23406D01*
X626154Y-23053D01*
X626507Y-22524D01*
X626631Y-21899D01*
X626507Y-21275D01*
X626154Y-20746D01*
X625624Y-20392D01*
X625000Y-20268D01*
D02*
G37*
G36*
X658465Y-28142D02*
X657840Y-28266D01*
X657311Y-28620D01*
X656957Y-29149D01*
X656833Y-29773D01*
X656957Y-30397D01*
X657311Y-30927D01*
X657840Y-31280D01*
X658465Y-31405D01*
X659089Y-31280D01*
X659618Y-30927D01*
X659972Y-30397D01*
X660096Y-29773D01*
X659972Y-29149D01*
X659618Y-28620D01*
X659089Y-28266D01*
X658465Y-28142D01*
D02*
G37*
G36*
X625000D02*
X624376Y-28266D01*
X623846Y-28620D01*
X623493Y-29149D01*
X623369Y-29773D01*
X623493Y-30397D01*
X623846Y-30927D01*
X624376Y-31280D01*
X625000Y-31405D01*
X625624Y-31280D01*
X626154Y-30927D01*
X626507Y-30397D01*
X626631Y-29773D01*
X626507Y-29149D01*
X626154Y-28620D01*
X625624Y-28266D01*
X625000Y-28142D01*
D02*
G37*
G36*
X640640Y-31369D02*
X639744Y-31547D01*
X638984Y-32055D01*
X638477Y-32814D01*
X638299Y-33710D01*
X638477Y-34606D01*
X638984Y-35366D01*
X639744Y-35873D01*
X640640Y-36051D01*
X641536Y-35873D01*
X642295Y-35366D01*
X642803Y-34606D01*
X642981Y-33710D01*
X642803Y-32814D01*
X642295Y-32055D01*
X641536Y-31547D01*
X640640Y-31369D01*
D02*
G37*
G36*
X658465Y-36016D02*
X657840Y-36140D01*
X657311Y-36494D01*
X656957Y-37023D01*
X656833Y-37647D01*
X656957Y-38271D01*
X657311Y-38801D01*
X657840Y-39154D01*
X658465Y-39279D01*
X659089Y-39154D01*
X659618Y-38801D01*
X659972Y-38271D01*
X660096Y-37647D01*
X659972Y-37023D01*
X659618Y-36494D01*
X659089Y-36140D01*
X658465Y-36016D01*
D02*
G37*
G36*
X625000Y-46449D02*
X624376Y-46573D01*
X623846Y-46927D01*
X623493Y-47456D01*
X623369Y-48080D01*
X623493Y-48705D01*
X623846Y-49234D01*
X624376Y-49588D01*
X625000Y-49712D01*
X625624Y-49588D01*
X626154Y-49234D01*
X626507Y-48705D01*
X626631Y-48080D01*
X626507Y-47456D01*
X626154Y-46927D01*
X625624Y-46573D01*
X625000Y-46449D01*
D02*
G37*
G36*
X65945Y-48417D02*
X65321Y-48542D01*
X64791Y-48895D01*
X64438Y-49424D01*
X64314Y-50049D01*
X64438Y-50673D01*
X64791Y-51202D01*
X65321Y-51556D01*
X65945Y-51680D01*
X66569Y-51556D01*
X67098Y-51202D01*
X67452Y-50673D01*
X67576Y-50049D01*
X67452Y-49424D01*
X67098Y-48895D01*
X66569Y-48542D01*
X65945Y-48417D01*
D02*
G37*
G36*
X82785Y-51645D02*
X81890Y-51823D01*
X81130Y-52330D01*
X80623Y-53090D01*
X80444Y-53986D01*
X80623Y-54882D01*
X81130Y-55641D01*
X81890Y-56149D01*
X82785Y-56327D01*
X83681Y-56149D01*
X84441Y-55641D01*
X84948Y-54882D01*
X85127Y-53986D01*
X84948Y-53090D01*
X84441Y-52330D01*
X83681Y-51823D01*
X82785Y-51645D01*
D02*
G37*
G36*
X99410Y-56292D02*
X98785Y-56416D01*
X98256Y-56769D01*
X97902Y-57299D01*
X97778Y-57923D01*
X97902Y-58547D01*
X98256Y-59076D01*
X98785Y-59430D01*
X99410Y-59554D01*
X100034Y-59430D01*
X100563Y-59076D01*
X100917Y-58547D01*
X101041Y-57923D01*
X100917Y-57299D01*
X100563Y-56769D01*
X100034Y-56416D01*
X99410Y-56292D01*
D02*
G37*
G36*
X65945D02*
X65321Y-56416D01*
X64791Y-56769D01*
X64438Y-57299D01*
X64314Y-57923D01*
X64438Y-58547D01*
X64791Y-59076D01*
X65321Y-59430D01*
X65945Y-59554D01*
X66569Y-59430D01*
X67098Y-59076D01*
X67452Y-58547D01*
X67576Y-57923D01*
X67452Y-57299D01*
X67098Y-56769D01*
X66569Y-56416D01*
X65945Y-56292D01*
D02*
G37*
G36*
X-23622Y-58408D02*
X-24246Y-58532D01*
X-24776Y-58886D01*
X-25129Y-59415D01*
X-25253Y-60039D01*
X-25129Y-60664D01*
X-24776Y-61193D01*
X-24667Y-61266D01*
Y-61766D01*
X-24776Y-61839D01*
X-25129Y-62368D01*
X-25253Y-62992D01*
X-25129Y-63616D01*
X-24776Y-64146D01*
X-24246Y-64499D01*
X-23622Y-64623D01*
X-22998Y-64499D01*
X-22468Y-64146D01*
X-22115Y-63616D01*
X-21991Y-62992D01*
X-22115Y-62368D01*
X-22468Y-61839D01*
X-22578Y-61766D01*
Y-61266D01*
X-22468Y-61193D01*
X-22115Y-60664D01*
X-21991Y-60039D01*
X-22115Y-59415D01*
X-22468Y-58886D01*
X-22998Y-58532D01*
X-23622Y-58408D01*
D02*
G37*
G36*
X651557Y-62675D02*
X650932Y-62799D01*
X650403Y-63153D01*
X650049Y-63682D01*
X649925Y-64306D01*
X650049Y-64931D01*
X650403Y-65460D01*
X650932Y-65813D01*
X651557Y-65938D01*
X652181Y-65813D01*
X652710Y-65460D01*
X653064Y-64931D01*
X653188Y-64306D01*
X653064Y-63682D01*
X652710Y-63153D01*
X652181Y-62799D01*
X651557Y-62675D01*
D02*
G37*
G36*
X99410Y-64166D02*
X98785Y-64290D01*
X98256Y-64643D01*
X97902Y-65173D01*
X97778Y-65797D01*
X97902Y-66421D01*
X98256Y-66950D01*
X98785Y-67304D01*
X99410Y-67428D01*
X100034Y-67304D01*
X100563Y-66950D01*
X100917Y-66421D01*
X101041Y-65797D01*
X100917Y-65173D01*
X100563Y-64643D01*
X100034Y-64290D01*
X99410Y-64166D01*
D02*
G37*
G36*
X65945D02*
X65321Y-64290D01*
X64791Y-64643D01*
X64438Y-65173D01*
X64314Y-65797D01*
X64438Y-66421D01*
X64791Y-66950D01*
X65321Y-67304D01*
X65945Y-67428D01*
X66569Y-67304D01*
X67098Y-66950D01*
X67452Y-66421D01*
X67576Y-65797D01*
X67452Y-65173D01*
X67098Y-64643D01*
X66569Y-64290D01*
X65945Y-64166D01*
D02*
G37*
G36*
X-23622Y-65298D02*
X-24246Y-65422D01*
X-24776Y-65776D01*
X-25129Y-66305D01*
X-25253Y-66929D01*
X-25129Y-67553D01*
X-24776Y-68083D01*
X-24246Y-68436D01*
X-23622Y-68560D01*
X-22998Y-68436D01*
X-22468Y-68083D01*
X-22115Y-67553D01*
X-21991Y-66929D01*
X-22115Y-66305D01*
X-22468Y-65776D01*
X-22998Y-65422D01*
X-23622Y-65298D01*
D02*
G37*
G36*
X574016Y-68841D02*
X573391Y-68965D01*
X572862Y-69319D01*
X572742Y-69499D01*
X572140D01*
X572020Y-69319D01*
X571490Y-68965D01*
X570866Y-68841D01*
X570242Y-68965D01*
X569713Y-69319D01*
X569359Y-69848D01*
X569235Y-70472D01*
X569359Y-71097D01*
X569599Y-71457D01*
X569359Y-71817D01*
X569235Y-72441D01*
X569359Y-73065D01*
X569599Y-73425D01*
X569359Y-73785D01*
X569235Y-74410D01*
X569359Y-75034D01*
X569713Y-75563D01*
X570242Y-75917D01*
X570866Y-76041D01*
X571490Y-75917D01*
X572020Y-75563D01*
X572140Y-75383D01*
X572742D01*
X572862Y-75563D01*
X573391Y-75917D01*
X574016Y-76041D01*
X574640Y-75917D01*
X575169Y-75563D01*
X575523Y-75034D01*
X575647Y-74410D01*
X575523Y-73785D01*
X575282Y-73425D01*
X575523Y-73065D01*
X575647Y-72441D01*
X575523Y-71817D01*
X575282Y-71457D01*
X575523Y-71097D01*
X575647Y-70472D01*
X575523Y-69848D01*
X575169Y-69319D01*
X574640Y-68965D01*
X574016Y-68841D01*
D02*
G37*
G36*
X82785Y-67393D02*
X81890Y-67571D01*
X81130Y-68079D01*
X80623Y-68838D01*
X80444Y-69734D01*
X80623Y-70630D01*
X81130Y-71389D01*
X81890Y-71897D01*
X82785Y-72075D01*
X83681Y-71897D01*
X84441Y-71389D01*
X84948Y-70630D01*
X85127Y-69734D01*
X84948Y-68838D01*
X84441Y-68079D01*
X83681Y-67571D01*
X82785Y-67393D01*
D02*
G37*
G36*
X-23622Y-69235D02*
X-24246Y-69359D01*
X-24776Y-69713D01*
X-25129Y-70242D01*
X-25253Y-70866D01*
X-25129Y-71490D01*
X-24776Y-72020D01*
X-24246Y-72373D01*
X-23622Y-72497D01*
X-22998Y-72373D01*
X-22468Y-72020D01*
X-22115Y-71490D01*
X-21991Y-70866D01*
X-22115Y-70242D01*
X-22468Y-69713D01*
X-22998Y-69359D01*
X-23622Y-69235D01*
D02*
G37*
G36*
X131890Y-71055D02*
X131265Y-71179D01*
X130736Y-71533D01*
X130383Y-72062D01*
X130258Y-72687D01*
X130383Y-73311D01*
X130736Y-73840D01*
X131265Y-74194D01*
X131890Y-74318D01*
X132514Y-74194D01*
X133043Y-73840D01*
X133397Y-73311D01*
X133521Y-72687D01*
X133397Y-72062D01*
X133043Y-71533D01*
X132514Y-71179D01*
X131890Y-71055D01*
D02*
G37*
G36*
X104528Y-90544D02*
X103903Y-90668D01*
X103374Y-91021D01*
X103020Y-91550D01*
X102896Y-92175D01*
X103020Y-92799D01*
X103374Y-93328D01*
X103903Y-93682D01*
X104528Y-93806D01*
X105152Y-93682D01*
X105681Y-93328D01*
X106035Y-92799D01*
X106159Y-92175D01*
X106035Y-91550D01*
X105681Y-91021D01*
X105152Y-90668D01*
X104528Y-90544D01*
D02*
G37*
G36*
X-23622Y-100731D02*
X-24246Y-100855D01*
X-24776Y-101209D01*
X-25129Y-101738D01*
X-25253Y-102362D01*
X-25129Y-102987D01*
X-24776Y-103516D01*
X-24246Y-103869D01*
X-23622Y-103994D01*
X-22998Y-103869D01*
X-22468Y-103516D01*
X-22115Y-102987D01*
X-21991Y-102362D01*
X-22115Y-101738D01*
X-22468Y-101209D01*
X-22998Y-100855D01*
X-23622Y-100731D01*
D02*
G37*
G36*
X310069Y-84117D02*
X308374Y-84250D01*
X306721Y-84647D01*
X305151Y-85298D01*
X303701Y-86186D01*
X302409Y-87290D01*
X301305Y-88583D01*
X300416Y-90032D01*
X299766Y-91603D01*
X299369Y-93256D01*
X299236Y-94950D01*
X299369Y-96645D01*
X299766Y-98298D01*
X300416Y-99869D01*
X301305Y-101318D01*
X302409Y-102611D01*
X303701Y-103715D01*
X305151Y-104603D01*
X306721Y-105254D01*
X308374Y-105650D01*
X310069Y-105784D01*
X311764Y-105650D01*
X313417Y-105254D01*
X314987Y-104603D01*
X316437Y-103715D01*
X317729Y-102611D01*
X318833Y-101318D01*
X319722Y-99869D01*
X320372Y-98298D01*
X320769Y-96645D01*
X320902Y-94950D01*
X320769Y-93256D01*
X320372Y-91603D01*
X319722Y-90032D01*
X318833Y-88583D01*
X317729Y-87290D01*
X316437Y-86186D01*
X314987Y-85298D01*
X313417Y-84647D01*
X311764Y-84250D01*
X310069Y-84117D01*
D02*
G37*
G36*
X71880D02*
X70185Y-84250D01*
X68532Y-84647D01*
X66962Y-85298D01*
X65512Y-86186D01*
X64220Y-87290D01*
X63116Y-88583D01*
X62227Y-90032D01*
X61577Y-91603D01*
X61180Y-93256D01*
X61046Y-94950D01*
X61180Y-96645D01*
X61577Y-98298D01*
X62227Y-99869D01*
X63116Y-101318D01*
X64220Y-102611D01*
X65512Y-103715D01*
X66962Y-104603D01*
X68532Y-105254D01*
X70185Y-105650D01*
X71880Y-105784D01*
X73575Y-105650D01*
X75228Y-105254D01*
X76798Y-104603D01*
X78248Y-103715D01*
X79540Y-102611D01*
X80644Y-101318D01*
X81533Y-99869D01*
X82183Y-98298D01*
X82580Y-96645D01*
X82713Y-94950D01*
X82580Y-93256D01*
X82183Y-91603D01*
X81533Y-90032D01*
X80644Y-88583D01*
X79540Y-87290D01*
X78248Y-86186D01*
X76798Y-85298D01*
X75228Y-84647D01*
X73575Y-84250D01*
X71880Y-84117D01*
D02*
G37*
G36*
X512795Y-102583D02*
X512171Y-102707D01*
X511642Y-103061D01*
X511288Y-103590D01*
X511164Y-104214D01*
X511288Y-104839D01*
X511642Y-105368D01*
X512171Y-105721D01*
X512795Y-105845D01*
X513420Y-105721D01*
X513949Y-105368D01*
X514302Y-104839D01*
X514427Y-104214D01*
X514302Y-103590D01*
X513949Y-103061D01*
X513420Y-102707D01*
X512795Y-102583D01*
D02*
G37*
G36*
X651545Y-84274D02*
X649851Y-84408D01*
X648198Y-84805D01*
X646627Y-85455D01*
X645178Y-86343D01*
X643885Y-87448D01*
X642781Y-88740D01*
X641893Y-90190D01*
X641242Y-91760D01*
X640845Y-93413D01*
X640712Y-95108D01*
X640845Y-96803D01*
X641242Y-98456D01*
X641893Y-100026D01*
X642781Y-101476D01*
X643885Y-102768D01*
X645178Y-103872D01*
X646627Y-104760D01*
X648198Y-105411D01*
X649851Y-105808D01*
X651545Y-105941D01*
X653240Y-105808D01*
X654893Y-105411D01*
X656463Y-104760D01*
X657913Y-103872D01*
X659206Y-102768D01*
X660310Y-101476D01*
X661198Y-100026D01*
X661848Y-98456D01*
X662245Y-96803D01*
X662379Y-95108D01*
X662245Y-93413D01*
X661848Y-91760D01*
X661198Y-90190D01*
X660310Y-88740D01*
X659206Y-87448D01*
X657913Y-86343D01*
X656463Y-85455D01*
X654893Y-84805D01*
X653240Y-84408D01*
X651545Y-84274D01*
D02*
G37*
G36*
X413356D02*
X411662Y-84408D01*
X410009Y-84805D01*
X408438Y-85455D01*
X406989Y-86343D01*
X405696Y-87448D01*
X404592Y-88740D01*
X403704Y-90190D01*
X403053Y-91760D01*
X402656Y-93413D01*
X402523Y-95108D01*
X402656Y-96803D01*
X403053Y-98456D01*
X403704Y-100026D01*
X404592Y-101476D01*
X405696Y-102768D01*
X406989Y-103872D01*
X408438Y-104760D01*
X410009Y-105411D01*
X411662Y-105808D01*
X413356Y-105941D01*
X415051Y-105808D01*
X416704Y-105411D01*
X418274Y-104760D01*
X419724Y-103872D01*
X421017Y-102768D01*
X422121Y-101476D01*
X423009Y-100026D01*
X423660Y-98456D01*
X424056Y-96803D01*
X424190Y-95108D01*
X424056Y-93413D01*
X423660Y-91760D01*
X423009Y-90190D01*
X422121Y-88740D01*
X421017Y-87448D01*
X419724Y-86343D01*
X418274Y-85455D01*
X416704Y-84805D01*
X415051Y-84408D01*
X413356Y-84274D01*
D02*
G37*
G36*
X269685Y-104520D02*
X269061Y-104644D01*
X268531Y-104998D01*
X268178Y-105527D01*
X268054Y-106151D01*
X268178Y-106775D01*
X268531Y-107305D01*
X269061Y-107658D01*
X269685Y-107782D01*
X270309Y-107658D01*
X270839Y-107305D01*
X271192Y-106775D01*
X271316Y-106151D01*
X271192Y-105527D01*
X270839Y-104998D01*
X270309Y-104644D01*
X269685Y-104520D01*
D02*
G37*
G36*
X-23622Y-104668D02*
X-24246Y-104792D01*
X-24776Y-105146D01*
X-25129Y-105675D01*
X-25253Y-106299D01*
X-25129Y-106923D01*
X-24776Y-107453D01*
X-24246Y-107806D01*
X-23622Y-107931D01*
X-22998Y-107806D01*
X-22468Y-107453D01*
X-22115Y-106923D01*
X-21991Y-106299D01*
X-22115Y-105675D01*
X-22468Y-105146D01*
X-22998Y-104792D01*
X-23622Y-104668D01*
D02*
G37*
G36*
X99347Y-108605D02*
X98722Y-108729D01*
X98193Y-109083D01*
X97839Y-109612D01*
X97715Y-110236D01*
X97362Y-110589D01*
X97284Y-110573D01*
X96659Y-110698D01*
X96130Y-111051D01*
X95776Y-111580D01*
X95652Y-112205D01*
X95776Y-112829D01*
X96130Y-113358D01*
X96659Y-113712D01*
X97284Y-113836D01*
X97908Y-113712D01*
X98437Y-113358D01*
X98791Y-112829D01*
X98855Y-112504D01*
X99372Y-112167D01*
X99605Y-112219D01*
X99673Y-112312D01*
X99776Y-112829D01*
X100130Y-113358D01*
X100659Y-113712D01*
X101284Y-113836D01*
X101908Y-113712D01*
X102437Y-113358D01*
X102791Y-112829D01*
X102915Y-112205D01*
X102791Y-111580D01*
X102437Y-111051D01*
X101908Y-110698D01*
X101415Y-110600D01*
X101126Y-110359D01*
X100956Y-110129D01*
X100854Y-109612D01*
X100500Y-109083D01*
X99971Y-108729D01*
X99347Y-108605D01*
D02*
G37*
G36*
X244094Y-107473D02*
X243470Y-107597D01*
X242941Y-107950D01*
X242587Y-108480D01*
X242463Y-109104D01*
X242587Y-109728D01*
X242941Y-110257D01*
X243470Y-110611D01*
X244094Y-110735D01*
X244719Y-110611D01*
X245248Y-110257D01*
X245602Y-109728D01*
X245726Y-109104D01*
X245602Y-108480D01*
X245248Y-107950D01*
X244719Y-107597D01*
X244094Y-107473D01*
D02*
G37*
G36*
X-23622Y-108605D02*
X-24246Y-108729D01*
X-24776Y-109083D01*
X-25129Y-109612D01*
X-25253Y-110236D01*
X-25129Y-110861D01*
X-24776Y-111390D01*
X-24246Y-111743D01*
X-23622Y-111868D01*
X-22998Y-111743D01*
X-22468Y-111390D01*
X-22115Y-110861D01*
X-21991Y-110236D01*
X-22115Y-109612D01*
X-22468Y-109083D01*
X-22998Y-108729D01*
X-23622Y-108605D01*
D02*
G37*
G36*
X354724Y-112148D02*
X354100Y-112272D01*
X353740Y-112513D01*
X353380Y-112272D01*
X352756Y-112148D01*
X352132Y-112272D01*
X351772Y-112513D01*
X351412Y-112272D01*
X350787Y-112148D01*
X350163Y-112272D01*
X349634Y-112626D01*
X349280Y-113155D01*
X349156Y-113779D01*
X349280Y-114404D01*
X349634Y-114933D01*
X349814Y-115054D01*
Y-115655D01*
X349634Y-115776D01*
X349280Y-116305D01*
X349156Y-116929D01*
X349280Y-117553D01*
X349634Y-118083D01*
X350163Y-118436D01*
X350787Y-118561D01*
X351412Y-118436D01*
X351772Y-118196D01*
X352132Y-118436D01*
X352756Y-118561D01*
X353380Y-118436D01*
X353740Y-118196D01*
X354100Y-118436D01*
X354724Y-118561D01*
X355349Y-118436D01*
X355878Y-118083D01*
X356232Y-117553D01*
X356356Y-116929D01*
X356232Y-116305D01*
X355878Y-115776D01*
X355697Y-115655D01*
Y-115054D01*
X355878Y-114933D01*
X356232Y-114404D01*
X356356Y-113779D01*
X356232Y-113155D01*
X355878Y-112626D01*
X355349Y-112272D01*
X354724Y-112148D01*
D02*
G37*
G36*
X107346Y-108605D02*
X106722Y-108729D01*
X106193Y-109083D01*
X105839Y-109612D01*
X105734Y-110141D01*
X105518Y-110433D01*
X105492Y-110459D01*
X105275Y-110588D01*
X104722Y-110698D01*
X104193Y-111051D01*
X103839Y-111580D01*
X103715Y-112205D01*
X103839Y-112829D01*
X104193Y-113358D01*
X104722Y-113712D01*
X105347Y-113836D01*
X105971Y-113712D01*
X106500Y-113358D01*
X106854Y-112829D01*
X106959Y-112300D01*
X107077Y-112140D01*
X107490Y-112080D01*
X107710Y-112129D01*
X107712Y-112132D01*
X107789Y-112289D01*
X107902Y-112861D01*
X108256Y-113390D01*
X108785Y-113743D01*
X109409Y-113868D01*
X110034Y-113743D01*
X110563Y-113390D01*
X110917Y-112861D01*
X111041Y-112236D01*
X110917Y-111612D01*
X110563Y-111083D01*
X110034Y-110729D01*
X109414Y-110606D01*
X109279Y-110576D01*
X109044Y-110340D01*
X108967Y-110183D01*
X108854Y-109612D01*
X108500Y-109083D01*
X107971Y-108729D01*
X107346Y-108605D01*
D02*
G37*
G36*
X309016Y-112355D02*
X308391Y-112479D01*
X307862Y-112832D01*
X307509Y-113362D01*
X307384Y-113986D01*
X307509Y-114610D01*
X307862Y-115139D01*
X308391Y-115493D01*
X309016Y-115617D01*
X309640Y-115493D01*
X310169Y-115139D01*
X310523Y-114610D01*
X310647Y-113986D01*
X310523Y-113362D01*
X310169Y-112832D01*
X309640Y-112479D01*
X309016Y-112355D01*
D02*
G37*
G36*
X483268Y-112394D02*
X482643Y-112518D01*
X482114Y-112872D01*
X481761Y-113401D01*
X481636Y-114025D01*
X481761Y-114649D01*
X482114Y-115179D01*
X482643Y-115532D01*
X483268Y-115656D01*
X483892Y-115532D01*
X484421Y-115179D01*
X484775Y-114649D01*
X484899Y-114025D01*
X484775Y-113401D01*
X484421Y-112872D01*
X483892Y-112518D01*
X483268Y-112394D01*
D02*
G37*
G36*
X487205Y-112425D02*
X486580Y-112549D01*
X486051Y-112903D01*
X485698Y-113432D01*
X485573Y-114057D01*
X485698Y-114681D01*
X486051Y-115210D01*
X486580Y-115564D01*
X487205Y-115688D01*
X487829Y-115564D01*
X488358Y-115210D01*
X488712Y-114681D01*
X488836Y-114057D01*
X488712Y-113432D01*
X488358Y-112903D01*
X487829Y-112549D01*
X487205Y-112425D01*
D02*
G37*
G36*
X-23622Y-112542D02*
X-24246Y-112666D01*
X-24776Y-113020D01*
X-25129Y-113549D01*
X-25253Y-114173D01*
X-25129Y-114797D01*
X-24776Y-115327D01*
X-24246Y-115680D01*
X-23622Y-115805D01*
X-22998Y-115680D01*
X-22468Y-115327D01*
X-22115Y-114797D01*
X-21991Y-114173D01*
X-22115Y-113549D01*
X-22468Y-113020D01*
X-22998Y-112666D01*
X-23622Y-112542D01*
D02*
G37*
G36*
X492319Y-113339D02*
X491695Y-113463D01*
X491166Y-113816D01*
X490812Y-114346D01*
X490688Y-114970D01*
X490812Y-115594D01*
X491166Y-116124D01*
X491695Y-116477D01*
X492319Y-116601D01*
X492944Y-116477D01*
X493473Y-116124D01*
X493827Y-115594D01*
X493951Y-114970D01*
X493827Y-114346D01*
X493473Y-113816D01*
X492944Y-113463D01*
X492319Y-113339D01*
D02*
G37*
G36*
X193898Y-113378D02*
X193273Y-113502D01*
X192744Y-113856D01*
X192391Y-114385D01*
X192266Y-115009D01*
X192391Y-115634D01*
X192744Y-116163D01*
X193273Y-116517D01*
X193898Y-116641D01*
X194522Y-116517D01*
X195051Y-116163D01*
X195405Y-115634D01*
X195529Y-115009D01*
X195405Y-114385D01*
X195051Y-113856D01*
X194522Y-113502D01*
X193898Y-113378D01*
D02*
G37*
G36*
X463551Y-114394D02*
X462927Y-114518D01*
X462398Y-114872D01*
X462044Y-115401D01*
X461920Y-116025D01*
X462044Y-116649D01*
X462398Y-117179D01*
X462927Y-117532D01*
X463551Y-117657D01*
X464176Y-117532D01*
X464705Y-117179D01*
X465058Y-116649D01*
X465182Y-116025D01*
X465058Y-115401D01*
X464705Y-114872D01*
X464176Y-114518D01*
X463551Y-114394D01*
D02*
G37*
G36*
X456742Y-114412D02*
X456118Y-114536D01*
X455589Y-114889D01*
X455235Y-115419D01*
X455111Y-116043D01*
X455235Y-116667D01*
X455589Y-117197D01*
X456118Y-117550D01*
X456742Y-117674D01*
X457366Y-117550D01*
X457896Y-117197D01*
X458249Y-116667D01*
X458373Y-116043D01*
X458249Y-115419D01*
X457896Y-114889D01*
X457366Y-114536D01*
X456742Y-114412D01*
D02*
G37*
G36*
X533878Y-116085D02*
X533254Y-116209D01*
X532725Y-116563D01*
X532371Y-117092D01*
X532247Y-117716D01*
X532371Y-118340D01*
X532725Y-118870D01*
X533254Y-119223D01*
X533878Y-119348D01*
X534502Y-119223D01*
X535032Y-118870D01*
X535385Y-118340D01*
X535509Y-117716D01*
X535385Y-117092D01*
X535032Y-116563D01*
X534502Y-116209D01*
X533878Y-116085D01*
D02*
G37*
G36*
X314961Y-117315D02*
X314336Y-117439D01*
X313807Y-117793D01*
X313454Y-118322D01*
X313329Y-118947D01*
X313454Y-119571D01*
X313807Y-120100D01*
X314336Y-120454D01*
X314961Y-120578D01*
X315585Y-120454D01*
X316114Y-120100D01*
X316468Y-119571D01*
X316592Y-118947D01*
X316468Y-118322D01*
X316114Y-117793D01*
X315585Y-117439D01*
X314961Y-117315D01*
D02*
G37*
G36*
X193898Y-118299D02*
X193273Y-118423D01*
X192744Y-118777D01*
X192391Y-119306D01*
X192266Y-119931D01*
X192391Y-120555D01*
X192744Y-121084D01*
X193273Y-121438D01*
X193898Y-121562D01*
X194522Y-121438D01*
X195051Y-121084D01*
X195405Y-120555D01*
X195529Y-119931D01*
X195405Y-119306D01*
X195051Y-118777D01*
X194522Y-118423D01*
X193898Y-118299D01*
D02*
G37*
G36*
X70866Y-120416D02*
X70242Y-120540D01*
X69713Y-120894D01*
X69359Y-121423D01*
X69235Y-122047D01*
X69359Y-122671D01*
X69713Y-123201D01*
X70242Y-123554D01*
X70866Y-123679D01*
X71490Y-123554D01*
X72020Y-123201D01*
X72373Y-122671D01*
X72497Y-122047D01*
X72373Y-121423D01*
X72020Y-120894D01*
X71490Y-120540D01*
X70866Y-120416D01*
D02*
G37*
G36*
X176115Y-116326D02*
X168609D01*
Y-123831D01*
X176115D01*
Y-116326D01*
D02*
G37*
G36*
X152362Y-116294D02*
X151383Y-116423D01*
X150470Y-116801D01*
X149686Y-117402D01*
X149084Y-118186D01*
X148706Y-119099D01*
X148577Y-120079D01*
X148706Y-121058D01*
X149084Y-121971D01*
X149686Y-122755D01*
X150470Y-123357D01*
X151383Y-123735D01*
X152362Y-123864D01*
X153342Y-123735D01*
X154255Y-123357D01*
X155039Y-122755D01*
X155640Y-121971D01*
X156018Y-121058D01*
X156147Y-120079D01*
X156018Y-119099D01*
X155640Y-118186D01*
X155039Y-117402D01*
X154255Y-116801D01*
X153342Y-116423D01*
X152362Y-116294D01*
D02*
G37*
G36*
X142362D02*
X141383Y-116423D01*
X140470Y-116801D01*
X139686Y-117402D01*
X139084Y-118186D01*
X138706Y-119099D01*
X138577Y-120079D01*
X138706Y-121058D01*
X139084Y-121971D01*
X139686Y-122755D01*
X140470Y-123357D01*
X141383Y-123735D01*
X142362Y-123864D01*
X143342Y-123735D01*
X144255Y-123357D01*
X145039Y-122755D01*
X145640Y-121971D01*
X146018Y-121058D01*
X146147Y-120079D01*
X146018Y-119099D01*
X145640Y-118186D01*
X145039Y-117402D01*
X144255Y-116801D01*
X143342Y-116423D01*
X142362Y-116294D01*
D02*
G37*
G36*
X267323Y-121252D02*
X266699Y-121376D01*
X266169Y-121730D01*
X265816Y-122259D01*
X265691Y-122883D01*
X265816Y-123508D01*
X266169Y-124037D01*
X266699Y-124391D01*
X267323Y-124515D01*
X267947Y-124391D01*
X268476Y-124037D01*
X268830Y-123508D01*
X268954Y-122883D01*
X268830Y-122259D01*
X268476Y-121730D01*
X267947Y-121376D01*
X267323Y-121252D01*
D02*
G37*
G36*
X412339Y-122174D02*
X411715Y-122298D01*
X411186Y-122652D01*
X410832Y-123181D01*
X410708Y-123805D01*
X410832Y-124430D01*
X411186Y-124959D01*
X411715Y-125313D01*
X412339Y-125437D01*
X412964Y-125313D01*
X413493Y-124959D01*
X413847Y-124430D01*
X413971Y-123805D01*
X413847Y-123181D01*
X413493Y-122652D01*
X412964Y-122298D01*
X412339Y-122174D01*
D02*
G37*
G36*
X309055Y-122236D02*
X308431Y-122361D01*
X307902Y-122714D01*
X307548Y-123243D01*
X307424Y-123868D01*
X307548Y-124492D01*
X307902Y-125021D01*
X308431Y-125375D01*
X309055Y-125499D01*
X309679Y-125375D01*
X310209Y-125021D01*
X310562Y-124492D01*
X310686Y-123868D01*
X310562Y-123243D01*
X310209Y-122714D01*
X309679Y-122361D01*
X309055Y-122236D01*
D02*
G37*
G36*
X117126Y-118290D02*
X116502Y-118414D01*
X115972Y-118768D01*
X115619Y-119297D01*
X115495Y-119921D01*
X115619Y-120546D01*
X115972Y-121075D01*
X116502Y-121428D01*
X117126Y-121553D01*
X117276Y-122013D01*
X117223Y-122292D01*
X117030Y-122434D01*
X116502Y-122539D01*
X115972Y-122893D01*
X115619Y-123422D01*
X115495Y-124047D01*
X115619Y-124671D01*
X115972Y-125200D01*
X116502Y-125554D01*
X117126Y-125678D01*
X117750Y-125554D01*
X118280Y-125200D01*
X118633Y-124671D01*
X118743Y-124118D01*
X118871Y-123901D01*
X118898Y-123875D01*
X119190Y-123659D01*
X119719Y-123554D01*
X120248Y-123200D01*
X120602Y-122671D01*
X120726Y-122047D01*
X120602Y-121422D01*
X120248Y-120893D01*
X119719Y-120539D01*
X119095Y-120415D01*
X119082Y-120418D01*
X118729Y-120064D01*
X118757Y-119921D01*
X118633Y-119297D01*
X118280Y-118768D01*
X117750Y-118414D01*
X117126Y-118290D01*
D02*
G37*
G36*
X597244Y-126321D02*
X596620Y-126446D01*
X596260Y-126686D01*
X595900Y-126446D01*
X595276Y-126321D01*
X594651Y-126446D01*
X594291Y-126686D01*
X593931Y-126446D01*
X593307Y-126321D01*
X592683Y-126446D01*
X592154Y-126799D01*
X591800Y-127329D01*
X591676Y-127953D01*
X591800Y-128577D01*
X592154Y-129106D01*
X592334Y-129227D01*
Y-129828D01*
X592154Y-129949D01*
X591800Y-130478D01*
X591676Y-131102D01*
X591800Y-131727D01*
X592154Y-132256D01*
X592683Y-132609D01*
X593307Y-132734D01*
X593931Y-132609D01*
X594291Y-132369D01*
X594651Y-132609D01*
X595276Y-132734D01*
X595900Y-132609D01*
X596260Y-132369D01*
X596620Y-132609D01*
X597244Y-132734D01*
X597868Y-132609D01*
X598398Y-132256D01*
X598751Y-131727D01*
X598876Y-131102D01*
X598751Y-130478D01*
X598398Y-129949D01*
X598217Y-129828D01*
Y-129227D01*
X598398Y-129106D01*
X598751Y-128577D01*
X598876Y-127953D01*
X598751Y-127329D01*
X598398Y-126799D01*
X597868Y-126446D01*
X597244Y-126321D01*
D02*
G37*
G36*
X576132Y-122159D02*
X575196Y-122346D01*
X574402Y-122876D01*
X573872Y-123670D01*
X573685Y-124606D01*
X573872Y-125543D01*
X574402Y-126337D01*
X575196Y-126867D01*
X576132Y-127053D01*
X577069Y-126867D01*
X577863Y-126337D01*
X578393Y-125543D01*
X578579Y-124606D01*
X578393Y-123670D01*
X577863Y-122876D01*
X577069Y-122346D01*
X576132Y-122159D01*
D02*
G37*
G36*
X330709Y-118841D02*
X330084Y-118965D01*
X329555Y-119319D01*
X329202Y-119848D01*
X329077Y-120473D01*
X329202Y-121097D01*
X329555Y-121626D01*
X329664Y-121699D01*
Y-122199D01*
X329555Y-122272D01*
X329202Y-122801D01*
X329077Y-123425D01*
X329202Y-124049D01*
X329555Y-124579D01*
X329664Y-124652D01*
Y-125152D01*
X329555Y-125224D01*
X329202Y-125754D01*
X329077Y-126378D01*
X329202Y-127002D01*
X329555Y-127532D01*
X330084Y-127885D01*
X330709Y-128009D01*
X331333Y-127885D01*
X331862Y-127532D01*
X332216Y-127002D01*
X332340Y-126378D01*
X332216Y-125754D01*
X331862Y-125224D01*
X331753Y-125152D01*
Y-124652D01*
X331862Y-124579D01*
X332216Y-124049D01*
X332340Y-123425D01*
X332216Y-122801D01*
X331862Y-122272D01*
X331753Y-122199D01*
Y-121699D01*
X331862Y-121626D01*
X332216Y-121097D01*
X332340Y-120473D01*
X332216Y-119848D01*
X331862Y-119319D01*
X331333Y-118965D01*
X330709Y-118841D01*
D02*
G37*
G36*
X534400Y-125337D02*
X533776Y-125461D01*
X533247Y-125815D01*
X532893Y-126344D01*
X532769Y-126969D01*
X532893Y-127593D01*
X533247Y-128122D01*
X533776Y-128476D01*
X534400Y-128600D01*
X535024Y-128476D01*
X535554Y-128122D01*
X535907Y-127593D01*
X536031Y-126969D01*
X535907Y-126344D01*
X535554Y-125815D01*
X535024Y-125461D01*
X534400Y-125337D01*
D02*
G37*
G36*
X375984Y-118447D02*
X375360Y-118572D01*
X374831Y-118925D01*
X374477Y-119454D01*
X374353Y-120079D01*
X374477Y-120703D01*
X374831Y-121232D01*
X375264Y-121522D01*
X375252Y-121916D01*
X375211Y-122042D01*
X374908Y-122103D01*
X374379Y-122456D01*
X374025Y-122985D01*
X373901Y-123610D01*
X374025Y-124234D01*
X374379Y-124763D01*
X374908Y-125117D01*
X375016Y-125138D01*
Y-125648D01*
X374966Y-125658D01*
X374437Y-126012D01*
X374083Y-126541D01*
X373959Y-127165D01*
X374083Y-127790D01*
X374437Y-128319D01*
X374966Y-128673D01*
X375590Y-128797D01*
X376215Y-128673D01*
X376744Y-128319D01*
X377098Y-127790D01*
X377222Y-127165D01*
X377098Y-126541D01*
X376744Y-126012D01*
X376215Y-125658D01*
X376107Y-125637D01*
Y-125127D01*
X376156Y-125117D01*
X376686Y-124763D01*
X377039Y-124234D01*
X377164Y-123610D01*
X377039Y-122985D01*
X376686Y-122456D01*
X376252Y-122167D01*
X376264Y-121772D01*
X376305Y-121646D01*
X376608Y-121586D01*
X377138Y-121232D01*
X377491Y-120703D01*
X377616Y-120079D01*
X377491Y-119454D01*
X377138Y-118925D01*
X376608Y-118572D01*
X375984Y-118447D01*
D02*
G37*
G36*
X309016Y-127028D02*
X308391Y-127152D01*
X307862Y-127506D01*
X307509Y-128035D01*
X307384Y-128659D01*
X307509Y-129283D01*
X307862Y-129813D01*
X308391Y-130166D01*
X309016Y-130290D01*
X309640Y-130166D01*
X310169Y-129813D01*
X310523Y-129283D01*
X310647Y-128659D01*
X310523Y-128035D01*
X310169Y-127506D01*
X309640Y-127152D01*
X309016Y-127028D01*
D02*
G37*
G36*
X524606Y-124205D02*
X523982Y-124329D01*
X523453Y-124683D01*
X523099Y-125212D01*
X522975Y-125836D01*
X523099Y-126461D01*
X523453Y-126990D01*
X523500Y-127022D01*
Y-127522D01*
X523404Y-127586D01*
X523050Y-128115D01*
X522926Y-128740D01*
X523050Y-129364D01*
X523404Y-129893D01*
X523933Y-130247D01*
X524557Y-130371D01*
X525181Y-130247D01*
X525711Y-129893D01*
X526064Y-129364D01*
X526188Y-128740D01*
X526064Y-128115D01*
X525711Y-127586D01*
X525663Y-127554D01*
Y-127054D01*
X525760Y-126990D01*
X526114Y-126461D01*
X526238Y-125836D01*
X526114Y-125212D01*
X525760Y-124683D01*
X525231Y-124329D01*
X524606Y-124205D01*
D02*
G37*
G36*
X237008Y-127945D02*
X236384Y-128069D01*
X235854Y-128423D01*
X235501Y-128952D01*
X235377Y-129576D01*
X235501Y-130201D01*
X235854Y-130730D01*
X236384Y-131084D01*
X237008Y-131208D01*
X237632Y-131084D01*
X238161Y-130730D01*
X238515Y-130201D01*
X238639Y-129576D01*
X238515Y-128952D01*
X238161Y-128423D01*
X237632Y-128069D01*
X237008Y-127945D01*
D02*
G37*
G36*
X267286Y-129066D02*
X266662Y-129190D01*
X266133Y-129543D01*
X265779Y-130073D01*
X265655Y-130697D01*
X265779Y-131321D01*
X266133Y-131851D01*
X266662Y-132204D01*
X267286Y-132328D01*
X267911Y-132204D01*
X268440Y-131851D01*
X268794Y-131321D01*
X268918Y-130697D01*
X268794Y-130073D01*
X268440Y-129543D01*
X267911Y-129190D01*
X267286Y-129066D01*
D02*
G37*
G36*
X240945Y-131833D02*
X240321Y-131957D01*
X239791Y-132311D01*
X239438Y-132840D01*
X239428Y-132888D01*
X238918D01*
X238909Y-132840D01*
X238555Y-132311D01*
X238026Y-131957D01*
X237402Y-131833D01*
X236777Y-131957D01*
X236248Y-132311D01*
X235894Y-132840D01*
X235770Y-133465D01*
X235894Y-134089D01*
X236248Y-134618D01*
X236777Y-134972D01*
X237402Y-135096D01*
X238026Y-134972D01*
X238555Y-134618D01*
X238909Y-134089D01*
X238918Y-134041D01*
X239428D01*
X239438Y-134089D01*
X239791Y-134618D01*
X240321Y-134972D01*
X240945Y-135096D01*
X241569Y-134972D01*
X242098Y-134618D01*
X242452Y-134089D01*
X242576Y-133465D01*
X242452Y-132840D01*
X242098Y-132311D01*
X241569Y-131957D01*
X240945Y-131833D01*
D02*
G37*
G36*
X505905Y-130110D02*
X505281Y-130235D01*
X504752Y-130588D01*
X504398Y-131117D01*
X504274Y-131742D01*
X504398Y-132366D01*
X504752Y-132895D01*
X505281Y-133249D01*
X505905Y-133373D01*
X506530Y-133249D01*
X507059Y-132895D01*
X507413Y-132366D01*
X507537Y-131742D01*
X507413Y-131117D01*
X507059Y-130588D01*
X506530Y-130235D01*
X505905Y-130110D01*
D02*
G37*
G36*
X117126Y-126415D02*
X116502Y-126540D01*
X115972Y-126893D01*
X115619Y-127422D01*
X115495Y-128047D01*
X115619Y-128671D01*
X115972Y-129200D01*
X116502Y-129554D01*
X117030Y-129659D01*
X117114Y-129721D01*
X117190Y-129903D01*
X117190Y-130193D01*
X117114Y-130373D01*
X117031Y-130435D01*
X116502Y-130540D01*
X115972Y-130894D01*
X115619Y-131423D01*
X115495Y-132047D01*
X115619Y-132671D01*
X115972Y-133201D01*
X116502Y-133554D01*
X117126Y-133679D01*
X117750Y-133554D01*
X118280Y-133201D01*
X118633Y-132671D01*
X118743Y-132118D01*
X118870Y-131903D01*
X118899Y-131874D01*
X119190Y-131659D01*
X119719Y-131554D01*
X120248Y-131200D01*
X120602Y-130671D01*
X120726Y-130047D01*
X120602Y-129422D01*
X120248Y-128893D01*
X119719Y-128540D01*
X119190Y-128434D01*
X118898Y-128218D01*
X118871Y-128192D01*
X118743Y-127975D01*
X118633Y-127422D01*
X118280Y-126893D01*
X117750Y-126540D01*
X117126Y-126415D01*
D02*
G37*
G36*
X475295Y-131981D02*
X474671Y-132105D01*
X474142Y-132458D01*
X473788Y-132987D01*
X473664Y-133612D01*
X473788Y-134236D01*
X474142Y-134765D01*
X474671Y-135119D01*
X475295Y-135243D01*
X475920Y-135119D01*
X476449Y-134765D01*
X476802Y-134236D01*
X476927Y-133612D01*
X476802Y-132987D01*
X476449Y-132458D01*
X475920Y-132105D01*
X475295Y-131981D01*
D02*
G37*
G36*
X405512Y-134980D02*
X404887Y-135104D01*
X404358Y-135458D01*
X404005Y-135987D01*
X403881Y-136611D01*
X404005Y-137235D01*
X404358Y-137765D01*
X404887Y-138118D01*
X405512Y-138242D01*
X406136Y-138118D01*
X406665Y-137765D01*
X407019Y-137235D01*
X407143Y-136611D01*
X407019Y-135987D01*
X406665Y-135458D01*
X406136Y-135104D01*
X405512Y-134980D01*
D02*
G37*
G36*
X399618Y-135196D02*
X398994Y-135320D01*
X398464Y-135674D01*
X398111Y-136203D01*
X397987Y-136828D01*
X398111Y-137452D01*
X398464Y-137981D01*
X398994Y-138335D01*
X399618Y-138459D01*
X400242Y-138335D01*
X400772Y-137981D01*
X401125Y-137452D01*
X401249Y-136828D01*
X401125Y-136203D01*
X400772Y-135674D01*
X400242Y-135320D01*
X399618Y-135196D01*
D02*
G37*
G36*
X469521Y-135983D02*
X468896Y-136108D01*
X468367Y-136461D01*
X468013Y-136990D01*
X467889Y-137615D01*
X468013Y-138239D01*
X468367Y-138768D01*
X468896Y-139122D01*
X469521Y-139246D01*
X470145Y-139122D01*
X470674Y-138768D01*
X471028Y-138239D01*
X471152Y-137615D01*
X471028Y-136990D01*
X470674Y-136461D01*
X470145Y-136108D01*
X469521Y-135983D01*
D02*
G37*
G36*
X379134Y-136164D02*
X378510Y-136288D01*
X377980Y-136642D01*
X377627Y-137171D01*
X377502Y-137795D01*
X377627Y-138420D01*
X377980Y-138949D01*
X378510Y-139302D01*
X379134Y-139427D01*
X379758Y-139302D01*
X380287Y-138949D01*
X380641Y-138420D01*
X380765Y-137795D01*
X380641Y-137171D01*
X380287Y-136642D01*
X379758Y-136288D01*
X379134Y-136164D01*
D02*
G37*
G36*
X109409Y-138480D02*
X108785Y-138604D01*
X108256Y-138958D01*
X107902Y-139487D01*
X107822Y-139890D01*
X107288Y-140015D01*
X106978Y-139795D01*
X106917Y-139487D01*
X106563Y-138958D01*
X106034Y-138604D01*
X105409Y-138480D01*
X104785Y-138604D01*
X104256Y-138958D01*
X103902Y-139487D01*
X103778Y-140111D01*
X103902Y-140735D01*
X104256Y-141265D01*
X104785Y-141618D01*
X105409Y-141742D01*
X105841Y-142049D01*
X105902Y-142357D01*
X106256Y-142886D01*
X106785Y-143239D01*
X107409Y-143364D01*
X108034Y-143239D01*
X108563Y-142886D01*
X108917Y-142357D01*
X109041Y-141732D01*
X109326Y-141726D01*
X109409Y-141742D01*
X110034Y-141618D01*
X110563Y-141265D01*
X110917Y-140735D01*
X111041Y-140111D01*
X110917Y-139487D01*
X110563Y-138958D01*
X110034Y-138604D01*
X109409Y-138480D01*
D02*
G37*
G36*
X101409D02*
X100785Y-138604D01*
X100256Y-138958D01*
X99902Y-139487D01*
X99822Y-139890D01*
X99288Y-140015D01*
X98978Y-139795D01*
X98917Y-139487D01*
X98563Y-138958D01*
X98034Y-138604D01*
X97409Y-138480D01*
X96785Y-138604D01*
X96256Y-138958D01*
X95902Y-139487D01*
X95778Y-140111D01*
X95902Y-140735D01*
X96256Y-141265D01*
X96785Y-141618D01*
X97409Y-141742D01*
X97841Y-142049D01*
X97902Y-142357D01*
X98256Y-142886D01*
X98785Y-143239D01*
X99410Y-143364D01*
X100034Y-143239D01*
X100563Y-142886D01*
X100917Y-142357D01*
X101041Y-141732D01*
X101326Y-141726D01*
X101409Y-141742D01*
X102034Y-141618D01*
X102563Y-141265D01*
X102917Y-140735D01*
X103041Y-140111D01*
X102917Y-139487D01*
X102563Y-138958D01*
X102034Y-138604D01*
X101409Y-138480D01*
D02*
G37*
G36*
X87254Y-137997D02*
X86630Y-138121D01*
X86101Y-138475D01*
X85747Y-139004D01*
X85623Y-139629D01*
X85747Y-140253D01*
X86101Y-140782D01*
X86630Y-141136D01*
X87254Y-141260D01*
X87879Y-141136D01*
X88115Y-140978D01*
X88413Y-141424D01*
X88943Y-141777D01*
X89567Y-141901D01*
X90191Y-141777D01*
X90720Y-141424D01*
X91074Y-140894D01*
X91198Y-140270D01*
X91074Y-139646D01*
X90720Y-139117D01*
X90191Y-138763D01*
X89567Y-138639D01*
X88943Y-138763D01*
X88706Y-138921D01*
X88408Y-138475D01*
X87879Y-138121D01*
X87254Y-137997D01*
D02*
G37*
G36*
X418898Y-142512D02*
X418273Y-142636D01*
X417808Y-142947D01*
X417609Y-142995D01*
X417162Y-142961D01*
X416730Y-142672D01*
X416106Y-142548D01*
X415481Y-142672D01*
X414952Y-143026D01*
X414598Y-143555D01*
X414474Y-144180D01*
X414598Y-144804D01*
X414952Y-145333D01*
X415481Y-145687D01*
X416106Y-145811D01*
X416730Y-145687D01*
X417195Y-145376D01*
X417394Y-145328D01*
X417841Y-145362D01*
X418273Y-145650D01*
X418898Y-145775D01*
X419522Y-145650D01*
X420051Y-145297D01*
X420405Y-144768D01*
X420529Y-144143D01*
X420405Y-143519D01*
X420051Y-142990D01*
X419522Y-142636D01*
X418898Y-142512D01*
D02*
G37*
G36*
X461319Y-142118D02*
X460695Y-142242D01*
X460165Y-142596D01*
X459812Y-143125D01*
X459688Y-143750D01*
X459812Y-144374D01*
X460165Y-144903D01*
X460695Y-145257D01*
X461319Y-145381D01*
X461943Y-145257D01*
X462472Y-144903D01*
X462826Y-144374D01*
X462950Y-143750D01*
X462826Y-143125D01*
X462472Y-142596D01*
X461943Y-142242D01*
X461319Y-142118D01*
D02*
G37*
G36*
X469291Y-142217D02*
X468667Y-142341D01*
X468138Y-142694D01*
X467784Y-143224D01*
X467660Y-143848D01*
X467784Y-144472D01*
X468138Y-145002D01*
X468667Y-145355D01*
X469291Y-145479D01*
X469916Y-145355D01*
X470445Y-145002D01*
X470798Y-144472D01*
X470923Y-143848D01*
X470798Y-143224D01*
X470445Y-142694D01*
X469916Y-142341D01*
X469291Y-142217D01*
D02*
G37*
G36*
X398568Y-143452D02*
X397944Y-143576D01*
X397415Y-143930D01*
X397061Y-144459D01*
X396937Y-145083D01*
X397061Y-145707D01*
X397415Y-146237D01*
X397944Y-146590D01*
X398568Y-146714D01*
X399193Y-146590D01*
X399722Y-146237D01*
X400075Y-145707D01*
X400200Y-145083D01*
X400075Y-144459D01*
X399722Y-143930D01*
X399193Y-143576D01*
X398568Y-143452D01*
D02*
G37*
G36*
X464328Y-144766D02*
X463704Y-144890D01*
X463175Y-145243D01*
X462821Y-145773D01*
X462697Y-146397D01*
X462821Y-147021D01*
X463175Y-147550D01*
X463704Y-147904D01*
X464328Y-148028D01*
X464953Y-147904D01*
X465482Y-147550D01*
X465836Y-147021D01*
X465960Y-146397D01*
X465836Y-145773D01*
X465482Y-145243D01*
X464953Y-144890D01*
X464328Y-144766D01*
D02*
G37*
G36*
X302362Y-152104D02*
X301174Y-152260D01*
X300068Y-152718D01*
X299117Y-153448D01*
X298388Y-154398D01*
X297929Y-155505D01*
X297773Y-156693D01*
X297929Y-157881D01*
X298388Y-158987D01*
X299117Y-159938D01*
X300068Y-160667D01*
X301174Y-161126D01*
X302362Y-161282D01*
X303550Y-161126D01*
X304657Y-160667D01*
X305607Y-159938D01*
X306337Y-158987D01*
X306795Y-157881D01*
X306951Y-156693D01*
X306795Y-155505D01*
X306337Y-154398D01*
X305607Y-153448D01*
X304657Y-152718D01*
X303550Y-152260D01*
X302362Y-152104D01*
D02*
G37*
G36*
X142520D02*
X141332Y-152260D01*
X140225Y-152718D01*
X139275Y-153448D01*
X138545Y-154398D01*
X138087Y-155505D01*
X137930Y-156693D01*
X138087Y-157881D01*
X138545Y-158987D01*
X139275Y-159938D01*
X140225Y-160667D01*
X141332Y-161126D01*
X142520Y-161282D01*
X143708Y-161126D01*
X144814Y-160667D01*
X145765Y-159938D01*
X146494Y-158987D01*
X146953Y-157881D01*
X147109Y-156693D01*
X146953Y-155505D01*
X146494Y-154398D01*
X145765Y-153448D01*
X144814Y-152718D01*
X143708Y-152260D01*
X142520Y-152104D01*
D02*
G37*
G36*
X-3728Y-152595D02*
X-13202D01*
Y-162069D01*
X-3728D01*
Y-152595D01*
D02*
G37*
G36*
X406528Y-156135D02*
X405903Y-156260D01*
X405374Y-156613D01*
X405020Y-157142D01*
X404896Y-157767D01*
X405020Y-158391D01*
X405374Y-158920D01*
X405783Y-159194D01*
X406004Y-159762D01*
X405973Y-159809D01*
X405849Y-160433D01*
X405973Y-161057D01*
X406327Y-161587D01*
X406436Y-161659D01*
Y-162159D01*
X406327Y-162232D01*
X406254Y-162341D01*
X405754D01*
X405681Y-162232D01*
X405152Y-161879D01*
X404528Y-161755D01*
X403903Y-161879D01*
X403374Y-162232D01*
X403020Y-162761D01*
X402896Y-163386D01*
X403020Y-164010D01*
X403374Y-164539D01*
X403903Y-164893D01*
X404528Y-165017D01*
X405152Y-164893D01*
X405681Y-164539D01*
X405754Y-164430D01*
X406254D01*
X406327Y-164539D01*
X406856Y-164893D01*
X407480Y-165017D01*
X408105Y-164893D01*
X408634Y-164539D01*
X408988Y-164010D01*
X409112Y-163386D01*
X408988Y-162761D01*
X408634Y-162232D01*
X408525Y-162159D01*
Y-161659D01*
X408634Y-161587D01*
X408988Y-161057D01*
X409112Y-160433D01*
X408988Y-159809D01*
X408634Y-159280D01*
X408225Y-159006D01*
X408003Y-158438D01*
X408035Y-158391D01*
X408159Y-157767D01*
X408035Y-157142D01*
X407681Y-156613D01*
X407152Y-156260D01*
X406528Y-156135D01*
D02*
G37*
G36*
X470285Y-158557D02*
X469550Y-158703D01*
X468927Y-159119D01*
X468511Y-159742D01*
X468365Y-160477D01*
X468511Y-161211D01*
X468927Y-161834D01*
X469550Y-162250D01*
X470285Y-162397D01*
X471019Y-162250D01*
X471642Y-161834D01*
X472058Y-161211D01*
X472204Y-160477D01*
X472058Y-159742D01*
X471642Y-159119D01*
X471019Y-158703D01*
X470285Y-158557D01*
D02*
G37*
G36*
X391545D02*
X390810Y-158703D01*
X390187Y-159119D01*
X389771Y-159742D01*
X389625Y-160477D01*
X389771Y-161211D01*
X390187Y-161834D01*
X390810Y-162250D01*
X391545Y-162397D01*
X392279Y-162250D01*
X392902Y-161834D01*
X393318Y-161211D01*
X393464Y-160477D01*
X393318Y-159742D01*
X392902Y-159119D01*
X392279Y-158703D01*
X391545Y-158557D01*
D02*
G37*
G36*
X533015Y-149026D02*
X531701Y-149155D01*
X530437Y-149539D01*
X529272Y-150162D01*
X528251Y-151000D01*
X527413Y-152021D01*
X526790Y-153185D01*
X526407Y-154449D01*
X526277Y-155764D01*
X526407Y-157079D01*
X526790Y-158343D01*
X527413Y-159507D01*
X528251Y-160529D01*
X529272Y-161366D01*
X530437Y-161989D01*
X531701Y-162373D01*
X533015Y-162502D01*
X534330Y-162373D01*
X535594Y-161989D01*
X536759Y-161366D01*
X537780Y-160529D01*
X538618Y-159507D01*
X539240Y-158343D01*
X539624Y-157079D01*
X539753Y-155764D01*
X539624Y-154449D01*
X539240Y-153185D01*
X538618Y-152021D01*
X537780Y-151000D01*
X536759Y-150162D01*
X535594Y-149539D01*
X534330Y-149155D01*
X533015Y-149026D01*
D02*
G37*
G36*
X336415D02*
X335101Y-149155D01*
X333837Y-149539D01*
X332672Y-150162D01*
X331651Y-151000D01*
X330813Y-152021D01*
X330190Y-153185D01*
X329807Y-154449D01*
X329677Y-155764D01*
X329807Y-157079D01*
X330190Y-158343D01*
X330813Y-159507D01*
X331651Y-160529D01*
X332672Y-161366D01*
X333837Y-161989D01*
X335101Y-162373D01*
X336415Y-162502D01*
X337730Y-162373D01*
X338994Y-161989D01*
X340159Y-161366D01*
X341180Y-160529D01*
X342018Y-159507D01*
X342640Y-158343D01*
X343024Y-157079D01*
X343153Y-155764D01*
X343024Y-154449D01*
X342640Y-153185D01*
X342018Y-152021D01*
X341180Y-151000D01*
X340159Y-150162D01*
X338994Y-149539D01*
X337730Y-149155D01*
X336415Y-149026D01*
D02*
G37*
G36*
X89567Y-164739D02*
X88943Y-164863D01*
X88762Y-164984D01*
X88321Y-165223D01*
X87792Y-164870D01*
X87167Y-164746D01*
X86543Y-164870D01*
X86014Y-165223D01*
X85660Y-165753D01*
X85536Y-166377D01*
X85660Y-167001D01*
X85835Y-167263D01*
X85917Y-167649D01*
X85707Y-167904D01*
X85409Y-168103D01*
X85055Y-168633D01*
X84931Y-169257D01*
X85055Y-169881D01*
X85409Y-170411D01*
X85938Y-170764D01*
X86562Y-170888D01*
X87186Y-170764D01*
X87716Y-170411D01*
X88069Y-169881D01*
X88194Y-169257D01*
X88069Y-168633D01*
X87894Y-168371D01*
X87813Y-167985D01*
X88013Y-167741D01*
X88414Y-167524D01*
X88943Y-167877D01*
X89567Y-168001D01*
X90192Y-167877D01*
X90721Y-167524D01*
X91074Y-166994D01*
X91199Y-166370D01*
X91074Y-165746D01*
X90721Y-165217D01*
X90192Y-164863D01*
X89567Y-164739D01*
D02*
G37*
G36*
X645669Y-155647D02*
X644176Y-155843D01*
X642784Y-156420D01*
X641589Y-157337D01*
X640672Y-158532D01*
X640095Y-159924D01*
X639899Y-161417D01*
X640095Y-162911D01*
X640672Y-164303D01*
X641589Y-165498D01*
X642784Y-166415D01*
X644176Y-166991D01*
X645669Y-167188D01*
X647163Y-166991D01*
X648555Y-166415D01*
X649750Y-165498D01*
X650667Y-164303D01*
X651243Y-162911D01*
X651440Y-161417D01*
X651243Y-159924D01*
X650667Y-158532D01*
X649750Y-157337D01*
X648555Y-156420D01*
X647163Y-155843D01*
X645669Y-155647D01*
D02*
G37*
G36*
X674409Y-154679D02*
X673095Y-154809D01*
X671831Y-155192D01*
X670666Y-155815D01*
X669645Y-156653D01*
X668807Y-157674D01*
X668184Y-158839D01*
X667801Y-160103D01*
X667671Y-161417D01*
X667801Y-162732D01*
X668184Y-163996D01*
X668807Y-165161D01*
X669645Y-166182D01*
X670666Y-167020D01*
X671831Y-167642D01*
X673095Y-168026D01*
X674409Y-168155D01*
X675724Y-168026D01*
X676988Y-167642D01*
X678153Y-167020D01*
X679174Y-166182D01*
X680012Y-165161D01*
X680634Y-163996D01*
X681018Y-162732D01*
X681147Y-161417D01*
X681018Y-160103D01*
X680634Y-158839D01*
X680012Y-157674D01*
X679174Y-156653D01*
X678153Y-155815D01*
X676988Y-155192D01*
X675724Y-154809D01*
X674409Y-154679D01*
D02*
G37*
G36*
X30512Y-168644D02*
X29888Y-168768D01*
X29358Y-169122D01*
X29005Y-169651D01*
X28881Y-170276D01*
X29005Y-170900D01*
X29358Y-171429D01*
X29888Y-171783D01*
X30512Y-171907D01*
X31136Y-171783D01*
X31665Y-171429D01*
X32019Y-170900D01*
X32143Y-170276D01*
X32019Y-169651D01*
X31665Y-169122D01*
X31136Y-168768D01*
X30512Y-168644D01*
D02*
G37*
G36*
X413440Y-173219D02*
X412815Y-173343D01*
X412286Y-173696D01*
X411787Y-173547D01*
X411667Y-173467D01*
X411043Y-173343D01*
X410418Y-173467D01*
X409889Y-173820D01*
X409536Y-174350D01*
X409411Y-174974D01*
X409536Y-175598D01*
X409889Y-176128D01*
X410418Y-176481D01*
X411043Y-176605D01*
X411667Y-176481D01*
X412196Y-176128D01*
X412696Y-176277D01*
X412815Y-176357D01*
X413440Y-176481D01*
X414064Y-176357D01*
X414593Y-176004D01*
X414947Y-175474D01*
X415071Y-174850D01*
X414947Y-174226D01*
X414593Y-173696D01*
X414064Y-173343D01*
X413440Y-173219D01*
D02*
G37*
G36*
X404823Y-173713D02*
X404199Y-173837D01*
X403911Y-174029D01*
X403543Y-174149D01*
X403176Y-174029D01*
X402888Y-173837D01*
X402264Y-173713D01*
X401640Y-173837D01*
X401110Y-174191D01*
X400757Y-174720D01*
X400632Y-175344D01*
X400757Y-175968D01*
X401110Y-176498D01*
X401640Y-176851D01*
X402264Y-176976D01*
X402888Y-176851D01*
X403176Y-176659D01*
X403543Y-176539D01*
X403911Y-176659D01*
X404199Y-176851D01*
X404823Y-176976D01*
X405447Y-176851D01*
X405976Y-176498D01*
X406330Y-175968D01*
X406454Y-175344D01*
X406330Y-174720D01*
X405976Y-174191D01*
X405447Y-173837D01*
X404823Y-173713D01*
D02*
G37*
G36*
X450850Y-172495D02*
X450225Y-172620D01*
X449696Y-172973D01*
X449342Y-173502D01*
X449218Y-174127D01*
X449342Y-174751D01*
X449696Y-175280D01*
X450225Y-175634D01*
X450850Y-175758D01*
X451474Y-175634D01*
X452003Y-175280D01*
X452357Y-174751D01*
X452481Y-174127D01*
X452357Y-173502D01*
X452003Y-172973D01*
X451474Y-172620D01*
X450850Y-172495D01*
D02*
G37*
G36*
X443898Y-173417D02*
X443273Y-173542D01*
X442744Y-173895D01*
X442390Y-174425D01*
X442266Y-175049D01*
X442390Y-175673D01*
X442744Y-176202D01*
X443273Y-176556D01*
X443898Y-176680D01*
X444522Y-176556D01*
X445051Y-176202D01*
X445405Y-175673D01*
X445529Y-175049D01*
X445405Y-174425D01*
X445051Y-173895D01*
X444522Y-173542D01*
X443898Y-173417D01*
D02*
G37*
G36*
X469390Y-173516D02*
X468765Y-173640D01*
X468236Y-173994D01*
X467883Y-174523D01*
X467758Y-175147D01*
X467883Y-175771D01*
X468236Y-176301D01*
X468765Y-176654D01*
X469390Y-176779D01*
X470014Y-176654D01*
X470543Y-176301D01*
X470897Y-175771D01*
X471021Y-175147D01*
X470897Y-174523D01*
X470543Y-173994D01*
X470014Y-173640D01*
X469390Y-173516D01*
D02*
G37*
G36*
X457283D02*
X456659Y-173640D01*
X456130Y-173994D01*
X455776Y-174523D01*
X455652Y-175147D01*
X455776Y-175771D01*
X456130Y-176301D01*
X456659Y-176654D01*
X457283Y-176779D01*
X457908Y-176654D01*
X458437Y-176301D01*
X458791Y-175771D01*
X458915Y-175147D01*
X458791Y-174523D01*
X458437Y-173994D01*
X457908Y-173640D01*
X457283Y-173516D01*
D02*
G37*
G36*
X417596Y-173565D02*
X416972Y-173690D01*
X416443Y-174043D01*
X416089Y-174573D01*
X415965Y-175197D01*
X416089Y-175821D01*
X416443Y-176350D01*
X416972Y-176704D01*
X417596Y-176828D01*
X418221Y-176704D01*
X418750Y-176350D01*
X419103Y-175821D01*
X419228Y-175197D01*
X419103Y-174573D01*
X418750Y-174043D01*
X418221Y-173690D01*
X417596Y-173565D01*
D02*
G37*
G36*
X86614D02*
X85990Y-173690D01*
X85461Y-174043D01*
X85107Y-174573D01*
X84983Y-175197D01*
X85107Y-175821D01*
X85461Y-176350D01*
X85990Y-176704D01*
X86614Y-176828D01*
X87239Y-176704D01*
X87768Y-176350D01*
X88121Y-175821D01*
X88245Y-175197D01*
X88121Y-174573D01*
X87768Y-174043D01*
X87239Y-173690D01*
X86614Y-173565D01*
D02*
G37*
G36*
X437697Y-173614D02*
X437073Y-173739D01*
X436543Y-174092D01*
X436190Y-174621D01*
X436065Y-175246D01*
X436190Y-175870D01*
X436543Y-176399D01*
X437073Y-176753D01*
X437697Y-176877D01*
X438321Y-176753D01*
X438850Y-176399D01*
X439204Y-175870D01*
X439328Y-175246D01*
X439204Y-174621D01*
X438850Y-174092D01*
X438321Y-173739D01*
X437697Y-173614D01*
D02*
G37*
G36*
X421596Y-173402D02*
X420972Y-173526D01*
X420443Y-173880D01*
X420089Y-174409D01*
X419965Y-175034D01*
X420089Y-175658D01*
X420443Y-176187D01*
X420972Y-176541D01*
X421596Y-176665D01*
X422221Y-176541D01*
X422750Y-176187D01*
X423057Y-176397D01*
X423059Y-176399D01*
X423588Y-176753D01*
X424213Y-176877D01*
X424837Y-176753D01*
X425366Y-176399D01*
X425439Y-176290D01*
X425939D01*
X426012Y-176399D01*
X426541Y-176753D01*
X427165Y-176877D01*
X427790Y-176753D01*
X428319Y-176399D01*
X428673Y-175870D01*
X428722Y-175624D01*
X429231D01*
X429300Y-175968D01*
X429654Y-176498D01*
X430183Y-176851D01*
X430807Y-176976D01*
X431431Y-176851D01*
X431961Y-176498D01*
X432065Y-176342D01*
X432666D01*
X432705Y-176399D01*
X433234Y-176753D01*
X433858Y-176877D01*
X434483Y-176753D01*
X435012Y-176399D01*
X435365Y-175870D01*
X435490Y-175246D01*
X435365Y-174621D01*
X435012Y-174092D01*
X434483Y-173739D01*
X433858Y-173614D01*
X433234Y-173739D01*
X432705Y-174092D01*
X432600Y-174248D01*
X431999D01*
X431961Y-174191D01*
X431431Y-173837D01*
X430807Y-173713D01*
X430183Y-173837D01*
X429654Y-174191D01*
X429300Y-174720D01*
X429251Y-174966D01*
X428741D01*
X428673Y-174621D01*
X428319Y-174092D01*
X427790Y-173739D01*
X427165Y-173614D01*
X426541Y-173739D01*
X426012Y-174092D01*
X425939Y-174201D01*
X425439D01*
X425366Y-174092D01*
X424837Y-173739D01*
X424213Y-173614D01*
X423588Y-173739D01*
X423059Y-174092D01*
X422751Y-173882D01*
X422750Y-173880D01*
X422221Y-173526D01*
X421596Y-173402D01*
D02*
G37*
G36*
X-23622Y-175534D02*
X-24246Y-175658D01*
X-24776Y-176012D01*
X-25129Y-176541D01*
X-25253Y-177165D01*
X-25129Y-177790D01*
X-24776Y-178319D01*
X-24246Y-178673D01*
X-23622Y-178797D01*
X-22998Y-178673D01*
X-22468Y-178319D01*
X-22115Y-177790D01*
X-21991Y-177165D01*
X-22115Y-176541D01*
X-22468Y-176012D01*
X-22998Y-175658D01*
X-23622Y-175534D01*
D02*
G37*
G36*
X74803Y-177503D02*
X74179Y-177627D01*
X73650Y-177980D01*
X73296Y-178510D01*
X73172Y-179134D01*
X73296Y-179758D01*
X73650Y-180287D01*
X74179Y-180641D01*
X74803Y-180765D01*
X75427Y-180641D01*
X75957Y-180287D01*
X76310Y-179758D01*
X76434Y-179134D01*
X76310Y-178510D01*
X75957Y-177980D01*
X75427Y-177627D01*
X74803Y-177503D01*
D02*
G37*
G36*
X63976D02*
X63352Y-177627D01*
X62823Y-177980D01*
X62469Y-178510D01*
X62345Y-179134D01*
X62469Y-179758D01*
X62823Y-180287D01*
X63352Y-180641D01*
X63976Y-180765D01*
X64601Y-180641D01*
X65130Y-180287D01*
X65484Y-179758D01*
X65608Y-179134D01*
X65484Y-178510D01*
X65130Y-177980D01*
X64601Y-177627D01*
X63976Y-177503D01*
D02*
G37*
G36*
X80709Y-178487D02*
X80084Y-178611D01*
X79555Y-178965D01*
X79202Y-179494D01*
X79077Y-180118D01*
X79202Y-180742D01*
X79555Y-181272D01*
X80084Y-181625D01*
X80709Y-181749D01*
X81333Y-181625D01*
X81862Y-181272D01*
X82216Y-180742D01*
X82340Y-180118D01*
X82216Y-179494D01*
X81862Y-178965D01*
X81333Y-178611D01*
X80709Y-178487D01*
D02*
G37*
G36*
X645669Y-172182D02*
X644176Y-172379D01*
X642784Y-172955D01*
X641589Y-173872D01*
X640672Y-175067D01*
X640095Y-176459D01*
X639899Y-177953D01*
X640095Y-179446D01*
X640672Y-180838D01*
X641589Y-182033D01*
X642784Y-182950D01*
X644176Y-183527D01*
X645669Y-183723D01*
X647163Y-183527D01*
X648555Y-182950D01*
X649750Y-182033D01*
X650667Y-180838D01*
X651243Y-179446D01*
X651440Y-177953D01*
X651243Y-176459D01*
X650667Y-175067D01*
X649750Y-173872D01*
X648555Y-172955D01*
X647163Y-172379D01*
X645669Y-172182D01*
D02*
G37*
G36*
X-23622Y-179471D02*
X-24246Y-179595D01*
X-24776Y-179949D01*
X-25129Y-180478D01*
X-25253Y-181102D01*
X-25129Y-181727D01*
X-24776Y-182256D01*
X-24667Y-182329D01*
Y-182829D01*
X-24776Y-182902D01*
X-25129Y-183431D01*
X-25253Y-184055D01*
X-25129Y-184679D01*
X-24776Y-185209D01*
X-24246Y-185562D01*
X-23622Y-185687D01*
X-22998Y-185562D01*
X-22468Y-185209D01*
X-22115Y-184679D01*
X-21991Y-184055D01*
X-22115Y-183431D01*
X-22468Y-182902D01*
X-22578Y-182829D01*
Y-182329D01*
X-22468Y-182256D01*
X-22115Y-181727D01*
X-21991Y-181102D01*
X-22115Y-180478D01*
X-22468Y-179949D01*
X-22998Y-179595D01*
X-23622Y-179471D01*
D02*
G37*
G36*
Y-186361D02*
X-24246Y-186485D01*
X-24776Y-186839D01*
X-25129Y-187368D01*
X-25253Y-187992D01*
X-25129Y-188616D01*
X-24776Y-189146D01*
X-24246Y-189499D01*
X-23622Y-189623D01*
X-22998Y-189499D01*
X-22468Y-189146D01*
X-22115Y-188616D01*
X-21991Y-187992D01*
X-22115Y-187368D01*
X-22468Y-186839D01*
X-22998Y-186485D01*
X-23622Y-186361D01*
D02*
G37*
G36*
X358661Y-192857D02*
X358037Y-192981D01*
X357508Y-193335D01*
X357154Y-193864D01*
X357030Y-194488D01*
X357154Y-195113D01*
X357508Y-195642D01*
X358037Y-195995D01*
X358661Y-196119D01*
X359286Y-195995D01*
X359815Y-195642D01*
X360169Y-195113D01*
X360293Y-194488D01*
X360169Y-193864D01*
X359815Y-193335D01*
X359286Y-192981D01*
X358661Y-192857D01*
D02*
G37*
G36*
X340904Y-192750D02*
X340170Y-192896D01*
X339547Y-193312D01*
X339131Y-193935D01*
X338984Y-194670D01*
X339131Y-195405D01*
X339547Y-196028D01*
X340170Y-196444D01*
X340904Y-196590D01*
X341639Y-196444D01*
X342262Y-196028D01*
X342678Y-195405D01*
X342824Y-194670D01*
X342678Y-193935D01*
X342262Y-193312D01*
X341639Y-192896D01*
X340904Y-192750D01*
D02*
G37*
G36*
X528395Y-192760D02*
X527661Y-192906D01*
X527038Y-193322D01*
X526622Y-193945D01*
X526475Y-194680D01*
X526622Y-195414D01*
X527038Y-196037D01*
X527661Y-196453D01*
X528395Y-196600D01*
X529130Y-196453D01*
X529753Y-196037D01*
X530169Y-195414D01*
X530315Y-194680D01*
X530169Y-193945D01*
X529753Y-193322D01*
X529130Y-192906D01*
X528395Y-192760D01*
D02*
G37*
G36*
X416835Y-194949D02*
X416210Y-195074D01*
X415681Y-195427D01*
X415328Y-195957D01*
X415203Y-196581D01*
X415328Y-197205D01*
X415681Y-197734D01*
X416210Y-198088D01*
X416835Y-198212D01*
X417459Y-198088D01*
X417988Y-197734D01*
X418342Y-197205D01*
X418466Y-196581D01*
X418342Y-195957D01*
X417988Y-195427D01*
X417459Y-195074D01*
X416835Y-194949D01*
D02*
G37*
G36*
X411811Y-195219D02*
X411187Y-195343D01*
X410658Y-195697D01*
X410304Y-196226D01*
X410180Y-196850D01*
X410304Y-197475D01*
X410658Y-198004D01*
X411187Y-198358D01*
X411811Y-198482D01*
X412435Y-198358D01*
X412965Y-198004D01*
X413318Y-197475D01*
X413442Y-196850D01*
X413318Y-196226D01*
X412965Y-195697D01*
X412435Y-195343D01*
X411811Y-195219D01*
D02*
G37*
G36*
X326966Y-193540D02*
X326342Y-193664D01*
X325813Y-194018D01*
X325459Y-194547D01*
X325335Y-195171D01*
X325459Y-195795D01*
X325813Y-196325D01*
X325580Y-196771D01*
X325461Y-196949D01*
X325337Y-197573D01*
X325461Y-198197D01*
X325815Y-198727D01*
X326344Y-199080D01*
X326969Y-199205D01*
X327593Y-199080D01*
X328122Y-198727D01*
X328476Y-198197D01*
X328600Y-197573D01*
X328476Y-196949D01*
X328122Y-196420D01*
X328355Y-195974D01*
X328474Y-195795D01*
X328598Y-195171D01*
X328474Y-194547D01*
X328120Y-194018D01*
X327591Y-193664D01*
X326966Y-193540D01*
D02*
G37*
G36*
X645669Y-188718D02*
X644176Y-188914D01*
X642784Y-189491D01*
X641589Y-190408D01*
X640672Y-191603D01*
X640095Y-192995D01*
X639899Y-194488D01*
X640095Y-195982D01*
X640672Y-197373D01*
X641589Y-198569D01*
X642784Y-199486D01*
X644176Y-200062D01*
X645669Y-200259D01*
X647163Y-200062D01*
X648555Y-199486D01*
X649750Y-198569D01*
X650667Y-197373D01*
X651243Y-195982D01*
X651440Y-194488D01*
X651243Y-192995D01*
X650667Y-191603D01*
X649750Y-190408D01*
X648555Y-189491D01*
X647163Y-188914D01*
X645669Y-188718D01*
D02*
G37*
G36*
X674409Y-187750D02*
X673095Y-187880D01*
X671831Y-188263D01*
X670666Y-188886D01*
X669645Y-189724D01*
X668807Y-190745D01*
X668184Y-191910D01*
X667801Y-193174D01*
X667671Y-194488D01*
X667801Y-195803D01*
X668184Y-197067D01*
X668807Y-198232D01*
X669645Y-199253D01*
X670666Y-200091D01*
X671831Y-200713D01*
X673095Y-201097D01*
X674409Y-201226D01*
X675724Y-201097D01*
X676988Y-200713D01*
X678153Y-200091D01*
X679174Y-199253D01*
X680012Y-198232D01*
X680634Y-197067D01*
X681018Y-195803D01*
X681147Y-194488D01*
X681018Y-193174D01*
X680634Y-191910D01*
X680012Y-190745D01*
X679174Y-189724D01*
X678153Y-188886D01*
X676988Y-188263D01*
X675724Y-187880D01*
X674409Y-187750D01*
D02*
G37*
G36*
X372016Y-199156D02*
X371392Y-199280D01*
X370862Y-199634D01*
X370509Y-200163D01*
X370384Y-200787D01*
X370509Y-201412D01*
X370862Y-201941D01*
X371392Y-202295D01*
X372016Y-202419D01*
X372640Y-202295D01*
X373169Y-201941D01*
X373523Y-201412D01*
X373647Y-200787D01*
X373523Y-200163D01*
X373169Y-199634D01*
X372640Y-199280D01*
X372016Y-199156D01*
D02*
G37*
G36*
X544291Y-194087D02*
X543667Y-194211D01*
X543138Y-194565D01*
X542784Y-195094D01*
X542660Y-195718D01*
X542784Y-196342D01*
X543025Y-196702D01*
X542784Y-197062D01*
X542660Y-197687D01*
X542784Y-198311D01*
X543025Y-198671D01*
X542784Y-199031D01*
X542660Y-199655D01*
X542784Y-200279D01*
X543025Y-200639D01*
X542784Y-200999D01*
X542660Y-201624D01*
X542784Y-202248D01*
X543138Y-202777D01*
X543667Y-203131D01*
X544291Y-203255D01*
X544916Y-203131D01*
X545445Y-202777D01*
X545798Y-202248D01*
X545923Y-201624D01*
X545798Y-200999D01*
X545558Y-200639D01*
X545798Y-200279D01*
X545923Y-199655D01*
X545798Y-199031D01*
X545558Y-198671D01*
X545798Y-198311D01*
X545923Y-197687D01*
X545798Y-197062D01*
X545558Y-196702D01*
X545798Y-196342D01*
X545923Y-195718D01*
X545798Y-195094D01*
X545445Y-194565D01*
X544916Y-194211D01*
X544291Y-194087D01*
D02*
G37*
G36*
X509842D02*
X509218Y-194211D01*
X508689Y-194565D01*
X508335Y-195094D01*
X508211Y-195718D01*
X508335Y-196342D01*
X508576Y-196702D01*
X508335Y-197062D01*
X508211Y-197687D01*
X508335Y-198311D01*
X508576Y-198671D01*
X508335Y-199031D01*
X508211Y-199655D01*
X508335Y-200279D01*
X508576Y-200639D01*
X508335Y-200999D01*
X508211Y-201624D01*
X508335Y-202248D01*
X508689Y-202777D01*
X509218Y-203131D01*
X509842Y-203255D01*
X510467Y-203131D01*
X510996Y-202777D01*
X511350Y-202248D01*
X511474Y-201624D01*
X511350Y-200999D01*
X511109Y-200639D01*
X511350Y-200279D01*
X511474Y-199655D01*
X511350Y-199031D01*
X511109Y-198671D01*
X511350Y-198311D01*
X511474Y-197687D01*
X511350Y-197062D01*
X511109Y-196702D01*
X511350Y-196342D01*
X511474Y-195718D01*
X511350Y-195094D01*
X510996Y-194565D01*
X510467Y-194211D01*
X509842Y-194087D01*
D02*
G37*
G36*
X366535Y-200731D02*
X365911Y-200855D01*
X365382Y-201209D01*
X365028Y-201738D01*
X364904Y-202362D01*
X365028Y-202987D01*
X365382Y-203516D01*
X365911Y-203869D01*
X366535Y-203994D01*
X367160Y-203869D01*
X367689Y-203516D01*
X368043Y-202987D01*
X368167Y-202362D01*
X368043Y-201738D01*
X367689Y-201209D01*
X367160Y-200855D01*
X366535Y-200731D01*
D02*
G37*
G36*
X361417Y-201518D02*
X360793Y-201642D01*
X360264Y-201996D01*
X359910Y-202525D01*
X359786Y-203150D01*
X359910Y-203774D01*
X360264Y-204303D01*
X360793Y-204657D01*
X361417Y-204781D01*
X362042Y-204657D01*
X362571Y-204303D01*
X362925Y-203774D01*
X363049Y-203150D01*
X362925Y-202525D01*
X362571Y-201996D01*
X362042Y-201642D01*
X361417Y-201518D01*
D02*
G37*
G36*
X379921Y-200109D02*
X379297Y-200233D01*
X378768Y-200587D01*
X378414Y-201116D01*
X378303Y-201675D01*
X378209Y-201843D01*
X378024Y-202028D01*
X377856Y-202122D01*
X377297Y-202233D01*
X376768Y-202587D01*
X376414Y-203116D01*
X376290Y-203740D01*
X376414Y-204364D01*
X376768Y-204894D01*
X377297Y-205247D01*
X377921Y-205371D01*
X378546Y-205247D01*
X379075Y-204894D01*
X379428Y-204364D01*
X379540Y-203805D01*
X379633Y-203637D01*
X379818Y-203452D01*
X379987Y-203359D01*
X380546Y-203247D01*
X381075Y-202894D01*
X381428Y-202364D01*
X381553Y-201740D01*
X381428Y-201116D01*
X381075Y-200587D01*
X380546Y-200233D01*
X379921Y-200109D01*
D02*
G37*
G36*
X658661Y-206636D02*
X658037Y-206761D01*
X657677Y-207001D01*
X657317Y-206761D01*
X656693Y-206636D01*
X656069Y-206761D01*
X655709Y-207001D01*
X655349Y-206761D01*
X654724Y-206636D01*
X654100Y-206761D01*
X653571Y-207114D01*
X653217Y-207643D01*
X653093Y-208268D01*
X653217Y-208892D01*
X653571Y-209421D01*
X653751Y-209542D01*
Y-210143D01*
X653571Y-210264D01*
X653217Y-210793D01*
X653093Y-211417D01*
X653217Y-212042D01*
X653571Y-212571D01*
X654100Y-212925D01*
X654724Y-213049D01*
X655349Y-212925D01*
X655709Y-212684D01*
X656069Y-212925D01*
X656693Y-213049D01*
X657317Y-212925D01*
X657677Y-212684D01*
X658037Y-212925D01*
X658661Y-213049D01*
X659286Y-212925D01*
X659815Y-212571D01*
X660169Y-212042D01*
X660293Y-211417D01*
X660169Y-210793D01*
X659815Y-210264D01*
X659634Y-210143D01*
Y-209542D01*
X659815Y-209421D01*
X660169Y-208892D01*
X660293Y-208268D01*
X660169Y-207643D01*
X659815Y-207114D01*
X659286Y-206761D01*
X658661Y-206636D01*
D02*
G37*
G36*
X361811Y-205455D02*
X361187Y-205579D01*
X360658Y-205933D01*
X360304Y-206462D01*
X360180Y-207087D01*
X360304Y-207711D01*
X360658Y-208240D01*
X361187Y-208594D01*
X361811Y-208718D01*
X362435Y-208594D01*
X362965Y-208240D01*
X363318Y-207711D01*
X363442Y-207087D01*
X363318Y-206462D01*
X362965Y-205933D01*
X362435Y-205579D01*
X361811Y-205455D01*
D02*
G37*
G36*
X86562Y-209551D02*
X85938Y-209676D01*
X85409Y-210029D01*
X85055Y-210558D01*
X84931Y-211183D01*
X85007Y-211565D01*
X85006Y-212075D01*
X84476Y-212429D01*
X84123Y-212958D01*
X83999Y-213583D01*
X84123Y-214207D01*
X84476Y-214736D01*
X85006Y-215090D01*
X85630Y-215214D01*
X86254Y-215090D01*
X86783Y-214736D01*
X87137Y-214207D01*
X87261Y-213583D01*
X87185Y-213200D01*
X87186Y-212690D01*
X87716Y-212336D01*
X88069Y-211807D01*
X88194Y-211183D01*
X88069Y-210558D01*
X87716Y-210029D01*
X87186Y-209676D01*
X86562Y-209551D01*
D02*
G37*
G36*
X-3728Y-205743D02*
X-13202D01*
Y-215217D01*
X-3728D01*
Y-205743D01*
D02*
G37*
G36*
X544291Y-213772D02*
X543667Y-213896D01*
X543138Y-214250D01*
X542784Y-214779D01*
X542660Y-215403D01*
X542784Y-216027D01*
X543138Y-216557D01*
X543667Y-216910D01*
X544291Y-217035D01*
X544916Y-216910D01*
X545445Y-216557D01*
X545798Y-216027D01*
X545923Y-215403D01*
X545798Y-214779D01*
X545445Y-214250D01*
X544916Y-213896D01*
X544291Y-213772D01*
D02*
G37*
G36*
X102528Y-209951D02*
X101903Y-210075D01*
X101374Y-210429D01*
X101020Y-210958D01*
X100896Y-211583D01*
X101020Y-212207D01*
X101191Y-212463D01*
X100964Y-213018D01*
X100754Y-213060D01*
X100224Y-213413D01*
X99871Y-213943D01*
X99767Y-214465D01*
X99566Y-214724D01*
X99308Y-214924D01*
X98785Y-215028D01*
X98256Y-215382D01*
X97902Y-215911D01*
X97778Y-216535D01*
X97902Y-217160D01*
X98256Y-217689D01*
X98785Y-218043D01*
X99410Y-218167D01*
X100034Y-218043D01*
X100563Y-217689D01*
X100917Y-217160D01*
X101021Y-216637D01*
X101221Y-216379D01*
X101479Y-216178D01*
X102002Y-216074D01*
X102532Y-215721D01*
X102885Y-215191D01*
X103009Y-214567D01*
X102885Y-213943D01*
X102714Y-213687D01*
X102941Y-213132D01*
X103152Y-213090D01*
X103681Y-212736D01*
X104035Y-212207D01*
X104159Y-211583D01*
X104035Y-210958D01*
X103681Y-210429D01*
X103152Y-210075D01*
X102528Y-209951D01*
D02*
G37*
G36*
X97125Y-217857D02*
X96501Y-217981D01*
X95972Y-218335D01*
X95618Y-218864D01*
X95494Y-219488D01*
X95618Y-220112D01*
X95972Y-220642D01*
X96501Y-220995D01*
X97125Y-221119D01*
X97750Y-220995D01*
X98279Y-220642D01*
X98632Y-220112D01*
X98757Y-219488D01*
X98632Y-218864D01*
X98279Y-218335D01*
X97750Y-217981D01*
X97125Y-217857D01*
D02*
G37*
G36*
X361531Y-221794D02*
X360906Y-221918D01*
X360377Y-222272D01*
X360284D01*
X359755Y-221918D01*
X359131Y-221794D01*
X358506Y-221918D01*
X357977Y-222272D01*
X357624Y-222801D01*
X357515Y-223347D01*
X357406Y-223483D01*
X357046Y-223709D01*
X356578Y-223616D01*
X356113Y-223335D01*
X356048Y-223011D01*
X355695Y-222482D01*
X355166Y-222129D01*
X354541Y-222004D01*
X353917Y-222129D01*
X353388Y-222482D01*
X353034Y-223011D01*
X352910Y-223636D01*
X353034Y-224260D01*
X353388Y-224789D01*
X353917Y-225143D01*
X354541Y-225267D01*
X355006Y-225548D01*
X355070Y-225871D01*
X355424Y-226400D01*
X355953Y-226754D01*
X356578Y-226878D01*
X357202Y-226754D01*
X357731Y-226400D01*
X358085Y-225871D01*
X358193Y-225325D01*
X358302Y-225189D01*
X358662Y-224963D01*
X359131Y-225057D01*
X359755Y-224932D01*
X360284Y-224579D01*
X360377D01*
X360906Y-224932D01*
X361531Y-225057D01*
X362155Y-224932D01*
X362684Y-224579D01*
X363038Y-224049D01*
X363162Y-223425D01*
X363038Y-222801D01*
X362684Y-222272D01*
X362155Y-221918D01*
X361531Y-221794D01*
D02*
G37*
G36*
X86614Y-219825D02*
X85990Y-219950D01*
X85461Y-220303D01*
X85107Y-220832D01*
X84983Y-221457D01*
X85107Y-222081D01*
X85461Y-222610D01*
X85990Y-222964D01*
X86614Y-223088D01*
X87239Y-222964D01*
X87768Y-222610D01*
X88121Y-222081D01*
X88245Y-221457D01*
X88121Y-220832D01*
X87768Y-220303D01*
X87239Y-219950D01*
X86614Y-219825D01*
D02*
G37*
G36*
X63976D02*
X63352Y-219950D01*
X62823Y-220303D01*
X62469Y-220832D01*
X62345Y-221457D01*
X62469Y-222081D01*
X62823Y-222610D01*
X63352Y-222964D01*
X63976Y-223088D01*
X64601Y-222964D01*
X65130Y-222610D01*
X65484Y-222081D01*
X65608Y-221457D01*
X65484Y-220832D01*
X65130Y-220303D01*
X64601Y-219950D01*
X63976Y-219825D01*
D02*
G37*
G36*
X544294Y-222616D02*
X543670Y-222740D01*
X543141Y-223094D01*
X542787Y-223623D01*
X542663Y-224248D01*
X542735Y-224608D01*
X542651Y-225084D01*
X542122Y-225437D01*
X541768Y-225967D01*
X541644Y-226591D01*
X541768Y-227215D01*
X542122Y-227744D01*
X542651Y-228098D01*
X543276Y-228222D01*
X543900Y-228098D01*
X544429Y-227744D01*
X544783Y-227215D01*
X544907Y-226591D01*
X544835Y-226230D01*
X544919Y-225755D01*
X545448Y-225401D01*
X545802Y-224872D01*
X545926Y-224248D01*
X545802Y-223623D01*
X545448Y-223094D01*
X544919Y-222740D01*
X544294Y-222616D01*
D02*
G37*
G36*
X86614Y-225731D02*
X85990Y-225855D01*
X85461Y-226209D01*
X85107Y-226738D01*
X84983Y-227362D01*
X85107Y-227987D01*
X85461Y-228516D01*
X85990Y-228869D01*
X86614Y-228994D01*
X87239Y-228869D01*
X87768Y-228516D01*
X88121Y-227987D01*
X88245Y-227362D01*
X88121Y-226738D01*
X87768Y-226209D01*
X87239Y-225855D01*
X86614Y-225731D01*
D02*
G37*
G36*
X611417Y-220781D02*
X610481Y-220968D01*
X609687Y-221498D01*
X609157Y-222292D01*
X608970Y-223228D01*
X609157Y-224165D01*
X609687Y-224959D01*
X610183Y-225290D01*
Y-225891D01*
X609687Y-226222D01*
X609157Y-227016D01*
X608970Y-227953D01*
X609157Y-228889D01*
X609687Y-229683D01*
X610481Y-230213D01*
X611417Y-230400D01*
X612354Y-230213D01*
X613148Y-229683D01*
X613678Y-228889D01*
X613864Y-227953D01*
X613678Y-227016D01*
X613148Y-226222D01*
X612652Y-225891D01*
Y-225290D01*
X613148Y-224959D01*
X613678Y-224165D01*
X613864Y-223228D01*
X613678Y-222292D01*
X613148Y-221498D01*
X612354Y-220968D01*
X611417Y-220781D01*
D02*
G37*
G36*
X604724Y-220388D02*
X603788Y-220574D01*
X602994Y-221104D01*
X602464Y-221898D01*
X602277Y-222835D01*
X602464Y-223771D01*
X602994Y-224565D01*
X603788Y-225095D01*
X604006Y-225139D01*
Y-225649D01*
X603788Y-225692D01*
X602994Y-226222D01*
X602464Y-227016D01*
X602277Y-227953D01*
X602464Y-228889D01*
X602994Y-229683D01*
X603788Y-230213D01*
X604724Y-230400D01*
X605661Y-230213D01*
X606455Y-229683D01*
X606985Y-228889D01*
X607171Y-227953D01*
X606985Y-227016D01*
X606455Y-226222D01*
X605661Y-225692D01*
X605443Y-225649D01*
Y-225139D01*
X605661Y-225095D01*
X606455Y-224565D01*
X606985Y-223771D01*
X607171Y-222835D01*
X606985Y-221898D01*
X606455Y-221104D01*
X605661Y-220574D01*
X604724Y-220388D01*
D02*
G37*
G36*
X599065Y-220585D02*
X598128Y-220771D01*
X597334Y-221301D01*
X596804Y-222095D01*
X596618Y-223031D01*
X596804Y-223968D01*
X597334Y-224762D01*
X598128Y-225292D01*
X598688Y-225404D01*
X598718Y-225410D01*
Y-225919D01*
X598665Y-225930D01*
X597883Y-226086D01*
X597089Y-226616D01*
X596558Y-227410D01*
X596372Y-228346D01*
X596558Y-229283D01*
X597089Y-230077D01*
X597883Y-230607D01*
X598819Y-230793D01*
X599755Y-230607D01*
X600549Y-230077D01*
X601080Y-229283D01*
X601266Y-228346D01*
X601080Y-227410D01*
X600549Y-226616D01*
X599755Y-226086D01*
X599196Y-225974D01*
X599165Y-225968D01*
Y-225459D01*
X599218Y-225448D01*
X600001Y-225292D01*
X600795Y-224762D01*
X601325Y-223968D01*
X601512Y-223031D01*
X601325Y-222095D01*
X600795Y-221301D01*
X600001Y-220771D01*
X599065Y-220585D01*
D02*
G37*
G36*
X-23622Y-227699D02*
X-24246Y-227823D01*
X-24776Y-228177D01*
X-25129Y-228706D01*
X-25253Y-229331D01*
X-25129Y-229955D01*
X-24776Y-230484D01*
X-24246Y-230838D01*
X-23622Y-230962D01*
X-22998Y-230838D01*
X-22468Y-230484D01*
X-22115Y-229955D01*
X-21991Y-229331D01*
X-22115Y-228706D01*
X-22468Y-228177D01*
X-22998Y-227823D01*
X-23622Y-227699D01*
D02*
G37*
G36*
X314503Y-223548D02*
X313878Y-223673D01*
X313349Y-224026D01*
X312995Y-224555D01*
X312871Y-225180D01*
X312995Y-225804D01*
X313349Y-226333D01*
X313462Y-226409D01*
X313711Y-226844D01*
X313579Y-227042D01*
X313357Y-227373D01*
X313233Y-227997D01*
X313357Y-228622D01*
X313711Y-229151D01*
X313723Y-229159D01*
X313836Y-229836D01*
X313719Y-230010D01*
X313595Y-230634D01*
X313719Y-231259D01*
X314073Y-231788D01*
X314602Y-232141D01*
X315226Y-232266D01*
X315851Y-232141D01*
X316380Y-231788D01*
X316734Y-231259D01*
X316858Y-230634D01*
X316734Y-230010D01*
X316380Y-229481D01*
X316368Y-229473D01*
X316255Y-228796D01*
X316372Y-228622D01*
X316496Y-227997D01*
X316372Y-227373D01*
X316018Y-226844D01*
X315905Y-226768D01*
X315656Y-226333D01*
X315789Y-226135D01*
X316010Y-225804D01*
X316134Y-225180D01*
X316010Y-224555D01*
X315656Y-224026D01*
X315127Y-223673D01*
X314503Y-223548D01*
D02*
G37*
G36*
X82677Y-230652D02*
X82053Y-230776D01*
X81524Y-231130D01*
X81170Y-231659D01*
X81046Y-232283D01*
X81170Y-232908D01*
X81524Y-233437D01*
X82053Y-233791D01*
X82677Y-233915D01*
X83302Y-233791D01*
X83831Y-233437D01*
X84184Y-232908D01*
X84308Y-232283D01*
X84184Y-231659D01*
X83831Y-231130D01*
X83302Y-230776D01*
X82677Y-230652D01*
D02*
G37*
G36*
X75787D02*
X75163Y-230776D01*
X74634Y-231130D01*
X74280Y-231659D01*
X74156Y-232283D01*
X74280Y-232908D01*
X74634Y-233437D01*
X75163Y-233791D01*
X75787Y-233915D01*
X76412Y-233791D01*
X76941Y-233437D01*
X77295Y-232908D01*
X77419Y-232283D01*
X77295Y-231659D01*
X76941Y-231130D01*
X76412Y-230776D01*
X75787Y-230652D01*
D02*
G37*
G36*
X361652Y-233573D02*
X361028Y-233698D01*
X360498Y-234051D01*
X360039Y-233838D01*
X359876Y-233729D01*
X359252Y-233605D01*
X358628Y-233729D01*
X358098Y-234083D01*
X358005D01*
X357476Y-233729D01*
X356852Y-233605D01*
X356228Y-233729D01*
X355698Y-234083D01*
X355606D01*
X355076Y-233729D01*
X354452Y-233605D01*
X353828Y-233729D01*
X353298Y-234083D01*
X352945Y-234612D01*
X352821Y-235236D01*
X352945Y-235860D01*
X353298Y-236390D01*
X353828Y-236743D01*
X354452Y-236868D01*
X355076Y-236743D01*
X355606Y-236390D01*
X355698D01*
X356228Y-236743D01*
X356852Y-236868D01*
X357476Y-236743D01*
X358005Y-236390D01*
X358098D01*
X358628Y-236743D01*
X359252Y-236868D01*
X359876Y-236743D01*
X360405Y-236390D01*
X360864Y-236603D01*
X361028Y-236712D01*
X361652Y-236836D01*
X362276Y-236712D01*
X362806Y-236358D01*
X363159Y-235829D01*
X363283Y-235205D01*
X363159Y-234580D01*
X362806Y-234051D01*
X362276Y-233698D01*
X361652Y-233573D01*
D02*
G37*
G36*
X544291Y-231636D02*
X543667Y-231761D01*
X543138Y-232114D01*
X542784Y-232643D01*
X542660Y-233268D01*
X542784Y-233892D01*
X543138Y-234421D01*
X543667Y-234775D01*
X544291Y-234899D01*
X544916Y-234775D01*
X545445Y-234421D01*
X545798Y-233892D01*
X545923Y-233268D01*
X545798Y-232643D01*
X545445Y-232114D01*
X544916Y-231761D01*
X544291Y-231636D01*
D02*
G37*
G36*
X-23622D02*
X-24246Y-231761D01*
X-24776Y-232114D01*
X-25129Y-232643D01*
X-25253Y-233268D01*
X-25129Y-233892D01*
X-24776Y-234421D01*
X-24246Y-234775D01*
X-23622Y-234899D01*
X-22998Y-234775D01*
X-22468Y-234421D01*
X-22115Y-233892D01*
X-21991Y-233268D01*
X-22115Y-232643D01*
X-22468Y-232114D01*
X-22998Y-231761D01*
X-23622Y-231636D01*
D02*
G37*
G36*
X323819Y-225731D02*
X323195Y-225855D01*
X322665Y-226209D01*
X322312Y-226738D01*
X322188Y-227362D01*
X322312Y-227987D01*
X322665Y-228516D01*
X323195Y-228869D01*
X323723Y-228975D01*
X323745Y-228991D01*
X323848Y-229592D01*
X323800Y-229672D01*
X323195Y-229792D01*
X322665Y-230146D01*
X322312Y-230675D01*
X322188Y-231299D01*
X322312Y-231924D01*
X322665Y-232453D01*
X323195Y-232806D01*
X323819Y-232931D01*
X324172Y-233283D01*
X324156Y-233362D01*
X324280Y-233986D01*
X324634Y-234516D01*
X325163Y-234869D01*
X325787Y-234994D01*
X326412Y-234869D01*
X326941Y-234516D01*
X327295Y-233986D01*
X327419Y-233362D01*
X327295Y-232738D01*
X326941Y-232209D01*
X326412Y-231855D01*
X325787Y-231731D01*
X325483Y-231427D01*
X325470Y-231376D01*
X325787Y-230994D01*
X326412Y-230869D01*
X326941Y-230516D01*
X327295Y-229987D01*
X327419Y-229362D01*
X327295Y-228738D01*
X326941Y-228209D01*
X326412Y-227855D01*
X325883Y-227750D01*
X325590Y-227534D01*
X325564Y-227507D01*
X325436Y-227291D01*
X325326Y-226738D01*
X324972Y-226209D01*
X324443Y-225855D01*
X323819Y-225731D01*
D02*
G37*
G36*
X288583Y-223959D02*
X287958Y-224083D01*
X287429Y-224437D01*
X287075Y-224966D01*
X286951Y-225590D01*
X287075Y-226215D01*
X287429Y-226744D01*
X287447Y-226756D01*
X287472Y-226855D01*
X287413Y-227334D01*
X287035Y-227587D01*
X286682Y-228116D01*
X286558Y-228740D01*
X286682Y-229364D01*
X287035Y-229894D01*
Y-229949D01*
X286682Y-230478D01*
X286558Y-231102D01*
X286682Y-231727D01*
X287026Y-232242D01*
X286904Y-232324D01*
X286550Y-232854D01*
X286426Y-233478D01*
X286550Y-234102D01*
X286904Y-234631D01*
X287433Y-234985D01*
X288057Y-235109D01*
X288681Y-234985D01*
X289211Y-234631D01*
X289564Y-234102D01*
X289688Y-233478D01*
X289564Y-232854D01*
X289220Y-232338D01*
X289342Y-232256D01*
X289696Y-231727D01*
X289820Y-231102D01*
X289696Y-230478D01*
X289342Y-229949D01*
Y-229894D01*
X289696Y-229364D01*
X289820Y-228740D01*
X289696Y-228116D01*
X289342Y-227587D01*
X289325Y-227575D01*
X289300Y-227476D01*
X289359Y-226996D01*
X289736Y-226744D01*
X290090Y-226215D01*
X290214Y-225590D01*
X290090Y-224966D01*
X289736Y-224437D01*
X289207Y-224083D01*
X288583Y-223959D01*
D02*
G37*
G36*
X564896Y-235168D02*
X564310Y-235284D01*
X563814Y-235616D01*
X563483Y-236112D01*
X563366Y-236697D01*
X563483Y-237282D01*
X563814Y-237779D01*
X564310Y-238110D01*
X564896Y-238227D01*
X565481Y-238110D01*
X565977Y-237779D01*
X566309Y-237282D01*
X566425Y-236697D01*
X566309Y-236112D01*
X565977Y-235616D01*
X565481Y-235284D01*
X564896Y-235168D01*
D02*
G37*
G36*
X-23622Y-235573D02*
X-24246Y-235698D01*
X-24776Y-236051D01*
X-25129Y-236580D01*
X-25253Y-237205D01*
X-25129Y-237829D01*
X-24776Y-238358D01*
X-24246Y-238712D01*
X-23622Y-238836D01*
X-22998Y-238712D01*
X-22468Y-238358D01*
X-22115Y-237829D01*
X-21991Y-237205D01*
X-22115Y-236580D01*
X-22468Y-236051D01*
X-22998Y-235698D01*
X-23622Y-235573D01*
D02*
G37*
G36*
X78740Y-236410D02*
X78116Y-236534D01*
X77587Y-236887D01*
X77233Y-237417D01*
X77109Y-238041D01*
X77233Y-238665D01*
X77587Y-239194D01*
X78116Y-239548D01*
X78740Y-239672D01*
X79364Y-239548D01*
X79894Y-239194D01*
X80247Y-238665D01*
X80371Y-238041D01*
X80247Y-237417D01*
X79894Y-236887D01*
X79364Y-236534D01*
X78740Y-236410D01*
D02*
G37*
G36*
X-23622Y-239510D02*
X-24246Y-239635D01*
X-24776Y-239988D01*
X-25129Y-240517D01*
X-25253Y-241142D01*
X-25129Y-241766D01*
X-24776Y-242295D01*
X-24246Y-242649D01*
X-23622Y-242773D01*
X-22998Y-242649D01*
X-22468Y-242295D01*
X-22115Y-241766D01*
X-21991Y-241142D01*
X-22115Y-240517D01*
X-22468Y-239988D01*
X-22998Y-239635D01*
X-23622Y-239510D01*
D02*
G37*
G36*
X323850Y-235573D02*
X323226Y-235698D01*
X322697Y-236051D01*
X322343Y-236580D01*
X322219Y-237205D01*
X322343Y-237829D01*
X322697Y-238358D01*
X323226Y-238712D01*
X323725Y-238811D01*
X323823Y-238901D01*
X323780Y-239517D01*
X323719Y-239568D01*
X323226Y-239666D01*
X322697Y-240020D01*
X322343Y-240549D01*
X322219Y-241173D01*
X322343Y-241797D01*
X322697Y-242327D01*
X323226Y-242680D01*
X323731Y-242781D01*
X324103Y-243114D01*
X324165Y-243252D01*
X324280Y-243829D01*
X324634Y-244358D01*
X325163Y-244712D01*
X325787Y-244836D01*
X326412Y-244712D01*
X326941Y-244358D01*
X327295Y-243829D01*
X327419Y-243205D01*
X327295Y-242580D01*
X326941Y-242051D01*
X326412Y-241698D01*
X325907Y-241597D01*
X325783Y-241486D01*
X325835Y-240880D01*
X325919Y-240810D01*
X326412Y-240712D01*
X326941Y-240358D01*
X327295Y-239829D01*
X327419Y-239205D01*
X327295Y-238580D01*
X326941Y-238051D01*
X326412Y-237698D01*
X325913Y-237598D01*
X325559Y-237275D01*
X325466Y-237127D01*
X325358Y-236580D01*
X325004Y-236051D01*
X324475Y-235698D01*
X323850Y-235573D01*
D02*
G37*
G36*
X640945Y-244825D02*
X640321Y-244950D01*
X639791Y-245303D01*
X639671Y-245484D01*
X639069D01*
X638949Y-245303D01*
X638420Y-244950D01*
X637795Y-244825D01*
X637171Y-244950D01*
X636642Y-245303D01*
X636288Y-245832D01*
X636164Y-246457D01*
X636288Y-247081D01*
X636529Y-247441D01*
X636288Y-247801D01*
X636164Y-248425D01*
X636288Y-249049D01*
X636529Y-249409D01*
X636288Y-249769D01*
X636164Y-250394D01*
X636288Y-251018D01*
X636642Y-251547D01*
X637171Y-251901D01*
X637795Y-252025D01*
X638420Y-251901D01*
X638949Y-251547D01*
X639069Y-251367D01*
X639671D01*
X639791Y-251547D01*
X640321Y-251901D01*
X640945Y-252025D01*
X641569Y-251901D01*
X642098Y-251547D01*
X642452Y-251018D01*
X642576Y-250394D01*
X642452Y-249769D01*
X642211Y-249409D01*
X642452Y-249049D01*
X642576Y-248425D01*
X642452Y-247801D01*
X642211Y-247441D01*
X642452Y-247081D01*
X642576Y-246457D01*
X642452Y-245832D01*
X642098Y-245303D01*
X641569Y-244950D01*
X640945Y-244825D01*
D02*
G37*
G36*
X314658Y-243143D02*
X314034Y-243268D01*
X313504Y-243621D01*
X313151Y-244150D01*
X313026Y-244775D01*
X313151Y-245399D01*
X313504Y-245928D01*
X314034Y-246282D01*
X314658Y-246406D01*
X315282Y-246282D01*
X315811Y-245928D01*
X316165Y-245399D01*
X316289Y-244775D01*
X316165Y-244150D01*
X315811Y-243621D01*
X315282Y-243268D01*
X314658Y-243143D01*
D02*
G37*
G36*
X288057Y-243464D02*
X287433Y-243588D01*
X286904Y-243941D01*
X286550Y-244471D01*
X286426Y-245095D01*
X286550Y-245719D01*
X286904Y-246249D01*
X286826Y-246798D01*
X286682Y-247013D01*
X286558Y-247638D01*
X286682Y-248262D01*
X287035Y-248791D01*
X287565Y-249145D01*
X288189Y-249269D01*
X288813Y-249145D01*
X289342Y-248791D01*
X289696Y-248262D01*
X289820Y-247638D01*
X289696Y-247013D01*
X289471Y-246676D01*
X289211Y-246249D01*
X289564Y-245719D01*
X289688Y-245095D01*
X289564Y-244471D01*
X289211Y-243941D01*
X288682Y-243588D01*
X288057Y-243464D01*
D02*
G37*
G36*
X555364Y-247778D02*
X554740Y-247902D01*
X554210Y-248256D01*
X553857Y-248785D01*
X553732Y-249410D01*
X553857Y-250034D01*
X554210Y-250563D01*
X554740Y-250917D01*
X555364Y-251041D01*
X555988Y-250917D01*
X556517Y-250563D01*
X556871Y-250034D01*
X556995Y-249410D01*
X556871Y-248785D01*
X556517Y-248256D01*
X555988Y-247902D01*
X555364Y-247778D01*
D02*
G37*
G36*
X360204Y-251353D02*
X359580Y-251477D01*
X359051Y-251831D01*
X358697Y-252360D01*
X358573Y-252984D01*
X358697Y-253608D01*
X359051Y-254138D01*
X359580Y-254491D01*
X360204Y-254616D01*
X360829Y-254491D01*
X361358Y-254138D01*
X361712Y-253608D01*
X361836Y-252984D01*
X361712Y-252360D01*
X361358Y-251831D01*
X360829Y-251477D01*
X360204Y-251353D01*
D02*
G37*
G36*
X360236Y-260554D02*
X359612Y-260679D01*
X359083Y-261032D01*
X358729Y-261561D01*
X358605Y-262186D01*
X358729Y-262810D01*
X359083Y-263339D01*
X359612Y-263693D01*
X360236Y-263817D01*
X360860Y-263693D01*
X361390Y-263339D01*
X361743Y-262810D01*
X361868Y-262186D01*
X361743Y-261561D01*
X361390Y-261032D01*
X360860Y-260679D01*
X360236Y-260554D01*
D02*
G37*
G36*
X121063Y-262000D02*
X120439Y-262124D01*
X119910Y-262478D01*
X119556Y-263007D01*
X119432Y-263632D01*
X119556Y-264256D01*
X119910Y-264785D01*
X120439Y-265139D01*
X121063Y-265263D01*
X121687Y-265139D01*
X122216Y-264785D01*
X122570Y-264256D01*
X122694Y-263632D01*
X122570Y-263007D01*
X122216Y-262478D01*
X121687Y-262124D01*
X121063Y-262000D01*
D02*
G37*
G36*
X106299D02*
X105675Y-262124D01*
X105146Y-262478D01*
X104792Y-263007D01*
X104668Y-263632D01*
X104792Y-264256D01*
X105146Y-264785D01*
X105675Y-265139D01*
X106299Y-265263D01*
X106923Y-265139D01*
X107453Y-264785D01*
X107806Y-264256D01*
X107931Y-263632D01*
X107806Y-263007D01*
X107453Y-262478D01*
X106923Y-262124D01*
X106299Y-262000D01*
D02*
G37*
G36*
X85630Y-262148D02*
X85006Y-262272D01*
X84476Y-262626D01*
X84123Y-263155D01*
X83999Y-263779D01*
X84123Y-264404D01*
X84476Y-264933D01*
Y-265026D01*
X84123Y-265555D01*
X83999Y-266179D01*
X84123Y-266804D01*
X84476Y-267333D01*
X85006Y-267687D01*
X85630Y-267811D01*
X86254Y-267687D01*
X86783Y-267333D01*
X87137Y-266804D01*
X87261Y-266179D01*
X87137Y-265555D01*
X86783Y-265026D01*
Y-264933D01*
X87137Y-264404D01*
X87261Y-263779D01*
X87137Y-263155D01*
X86783Y-262626D01*
X86254Y-262272D01*
X85630Y-262148D01*
D02*
G37*
G36*
X-3728Y-258893D02*
X-13202D01*
Y-268367D01*
X-3728D01*
Y-258893D01*
D02*
G37*
G36*
X360236Y-264554D02*
X359612Y-264679D01*
X359083Y-265032D01*
X358729Y-265562D01*
X358605Y-266186D01*
X358729Y-266810D01*
X359083Y-267339D01*
Y-267432D01*
X358729Y-267962D01*
X358605Y-268586D01*
X358729Y-269210D01*
X359083Y-269739D01*
X359612Y-270093D01*
X360236Y-270217D01*
X360860Y-270093D01*
X361390Y-269739D01*
X361743Y-269210D01*
X361868Y-268586D01*
X361743Y-267962D01*
X361390Y-267432D01*
Y-267339D01*
X361743Y-266810D01*
X361868Y-266186D01*
X361743Y-265562D01*
X361390Y-265032D01*
X360860Y-264679D01*
X360236Y-264554D01*
D02*
G37*
G36*
X512402Y-260327D02*
X511777Y-260451D01*
X511248Y-260805D01*
X510894Y-261334D01*
X510770Y-261958D01*
X510894Y-262583D01*
X511248Y-263112D01*
X511428Y-263232D01*
Y-263834D01*
X511248Y-263954D01*
X510894Y-264484D01*
X510770Y-265108D01*
X510894Y-265732D01*
X511248Y-266261D01*
X511355Y-266333D01*
X511389Y-266912D01*
X511036Y-267441D01*
X510912Y-268065D01*
X511036Y-268689D01*
X511389Y-269219D01*
X511504Y-269295D01*
Y-269309D01*
X511150Y-269838D01*
X511026Y-270462D01*
X511150Y-271087D01*
X511504Y-271616D01*
X512033Y-271970D01*
X512657Y-272094D01*
X513282Y-271970D01*
X513811Y-271616D01*
X514164Y-271087D01*
X514289Y-270462D01*
X514164Y-269838D01*
X513811Y-269309D01*
X513696Y-269233D01*
Y-269219D01*
X514050Y-268689D01*
X514174Y-268065D01*
X514050Y-267441D01*
X513696Y-266912D01*
X513589Y-266840D01*
X513555Y-266261D01*
X513909Y-265732D01*
X514033Y-265108D01*
X513909Y-264484D01*
X513555Y-263954D01*
X513375Y-263834D01*
Y-263232D01*
X513555Y-263112D01*
X513909Y-262583D01*
X514033Y-261958D01*
X513909Y-261334D01*
X513555Y-260805D01*
X513026Y-260451D01*
X512402Y-260327D01*
D02*
G37*
G36*
X360236Y-270858D02*
X359612Y-270983D01*
X359083Y-271336D01*
X358729Y-271866D01*
X358605Y-272490D01*
X358729Y-273114D01*
X359083Y-273643D01*
X359612Y-273997D01*
X360236Y-274121D01*
X360860Y-273997D01*
X361390Y-273643D01*
X361743Y-273114D01*
X361868Y-272490D01*
X361743Y-271866D01*
X361390Y-271336D01*
X360860Y-270983D01*
X360236Y-270858D01*
D02*
G37*
G36*
X320866D02*
X320242Y-270983D01*
X319713Y-271336D01*
X319359Y-271866D01*
X319235Y-272490D01*
X319359Y-273114D01*
X319713Y-273643D01*
X320242Y-273997D01*
X320866Y-274121D01*
X321490Y-273997D01*
X322020Y-273643D01*
X322373Y-273114D01*
X322498Y-272490D01*
X322373Y-271866D01*
X322020Y-271336D01*
X321490Y-270983D01*
X320866Y-270858D01*
D02*
G37*
G36*
X340904Y-271490D02*
X340170Y-271636D01*
X339547Y-272052D01*
X339131Y-272675D01*
X338984Y-273410D01*
X339131Y-274145D01*
X339547Y-274768D01*
X340170Y-275184D01*
X340904Y-275330D01*
X341639Y-275184D01*
X342262Y-274768D01*
X342678Y-274145D01*
X342824Y-273410D01*
X342678Y-272675D01*
X342262Y-272052D01*
X341639Y-271636D01*
X340904Y-271490D01*
D02*
G37*
G36*
X528395Y-271500D02*
X527661Y-271646D01*
X527038Y-272062D01*
X526622Y-272685D01*
X526475Y-273420D01*
X526622Y-274154D01*
X527038Y-274777D01*
X527661Y-275194D01*
X528395Y-275340D01*
X529130Y-275194D01*
X529753Y-274777D01*
X530169Y-274154D01*
X530315Y-273420D01*
X530169Y-272685D01*
X529753Y-272062D01*
X529130Y-271646D01*
X528395Y-271500D01*
D02*
G37*
G36*
X87598Y-273959D02*
X86974Y-274083D01*
X86445Y-274437D01*
X86091Y-274966D01*
X85967Y-275590D01*
X86091Y-276215D01*
X86445Y-276744D01*
X86974Y-277098D01*
X87598Y-277222D01*
X88223Y-277098D01*
X88752Y-276744D01*
X89106Y-276215D01*
X89230Y-275590D01*
X89106Y-274966D01*
X88752Y-274437D01*
X88223Y-274083D01*
X87598Y-273959D01*
D02*
G37*
G36*
X63976D02*
X63352Y-274083D01*
X62823Y-274437D01*
X62469Y-274966D01*
X62345Y-275590D01*
X62469Y-276215D01*
X62823Y-276744D01*
X63352Y-277098D01*
X63976Y-277222D01*
X64601Y-277098D01*
X65130Y-276744D01*
X65484Y-276215D01*
X65608Y-275590D01*
X65484Y-274966D01*
X65130Y-274437D01*
X64601Y-274083D01*
X63976Y-273959D01*
D02*
G37*
G36*
X87598Y-279865D02*
X86974Y-279989D01*
X86445Y-280343D01*
X86091Y-280872D01*
X85967Y-281496D01*
X86091Y-282120D01*
X86445Y-282650D01*
X86974Y-283003D01*
X87598Y-283127D01*
X88223Y-283003D01*
X88752Y-282650D01*
X89106Y-282120D01*
X89230Y-281496D01*
X89106Y-280872D01*
X88752Y-280343D01*
X88223Y-279989D01*
X87598Y-279865D01*
D02*
G37*
G36*
X-23622Y-280849D02*
X-24246Y-280973D01*
X-24776Y-281327D01*
X-25129Y-281856D01*
X-25253Y-282480D01*
X-25129Y-283105D01*
X-24776Y-283634D01*
X-24246Y-283987D01*
X-23622Y-284112D01*
X-22998Y-283987D01*
X-22468Y-283634D01*
X-22115Y-283105D01*
X-21991Y-282480D01*
X-22115Y-281856D01*
X-22468Y-281327D01*
X-22998Y-280973D01*
X-23622Y-280849D01*
D02*
G37*
G36*
X26575Y-281833D02*
X25951Y-281957D01*
X25421Y-282311D01*
X25068Y-282840D01*
X24943Y-283465D01*
X25068Y-284089D01*
X25421Y-284618D01*
X25951Y-284972D01*
X26575Y-285096D01*
X27199Y-284972D01*
X27728Y-284618D01*
X28082Y-284089D01*
X28206Y-283465D01*
X28082Y-282840D01*
X27728Y-282311D01*
X27199Y-281957D01*
X26575Y-281833D01*
D02*
G37*
G36*
X75787Y-283802D02*
X75163Y-283926D01*
X74634Y-284279D01*
X74280Y-284809D01*
X74156Y-285433D01*
X74280Y-286057D01*
X74634Y-286587D01*
X75163Y-286940D01*
X75787Y-287064D01*
X76412Y-286940D01*
X76941Y-286587D01*
X77295Y-286057D01*
X77419Y-285433D01*
X77295Y-284809D01*
X76941Y-284279D01*
X76412Y-283926D01*
X75787Y-283802D01*
D02*
G37*
G36*
X-23622Y-284786D02*
X-24246Y-284910D01*
X-24776Y-285264D01*
X-25129Y-285793D01*
X-25253Y-286417D01*
X-25129Y-287042D01*
X-24776Y-287571D01*
X-24246Y-287925D01*
X-23622Y-288049D01*
X-22998Y-287925D01*
X-22468Y-287571D01*
X-22115Y-287042D01*
X-21991Y-286417D01*
X-22115Y-285793D01*
X-22468Y-285264D01*
X-22998Y-284910D01*
X-23622Y-284786D01*
D02*
G37*
G36*
X81880Y-285951D02*
X81255Y-286075D01*
X80726Y-286429D01*
X80372Y-286958D01*
X80248Y-287582D01*
X80372Y-288207D01*
X80726Y-288736D01*
X81255Y-289090D01*
X81880Y-289214D01*
X82504Y-289090D01*
X83033Y-288736D01*
X83387Y-288207D01*
X83511Y-287582D01*
X83387Y-286958D01*
X83033Y-286429D01*
X82504Y-286075D01*
X81880Y-285951D01*
D02*
G37*
G36*
X-23622Y-288723D02*
X-24246Y-288847D01*
X-24776Y-289201D01*
X-25129Y-289730D01*
X-25253Y-290354D01*
X-25129Y-290979D01*
X-24776Y-291508D01*
X-24246Y-291862D01*
X-23622Y-291986D01*
X-22998Y-291862D01*
X-22468Y-291508D01*
X-22115Y-290979D01*
X-21991Y-290354D01*
X-22115Y-289730D01*
X-22468Y-289201D01*
X-22998Y-288847D01*
X-23622Y-288723D01*
D02*
G37*
G36*
Y-292660D02*
X-24246Y-292784D01*
X-24776Y-293138D01*
X-25129Y-293667D01*
X-25253Y-294291D01*
X-25129Y-294916D01*
X-24776Y-295445D01*
X-24246Y-295798D01*
X-23622Y-295923D01*
X-22998Y-295798D01*
X-22468Y-295445D01*
X-22115Y-294916D01*
X-21991Y-294291D01*
X-22115Y-293667D01*
X-22468Y-293138D01*
X-22998Y-292784D01*
X-23622Y-292660D01*
D02*
G37*
G36*
X675591Y-297188D02*
X674966Y-297312D01*
X674606Y-297552D01*
X674246Y-297312D01*
X673622Y-297188D01*
X672998Y-297312D01*
X672638Y-297552D01*
X672278Y-297312D01*
X671654Y-297188D01*
X671029Y-297312D01*
X670500Y-297665D01*
X670146Y-298195D01*
X670022Y-298819D01*
X670146Y-299443D01*
X670500Y-299972D01*
X670681Y-300093D01*
Y-300694D01*
X670500Y-300815D01*
X670146Y-301344D01*
X670022Y-301969D01*
X670146Y-302593D01*
X670500Y-303122D01*
X671029Y-303476D01*
X671654Y-303600D01*
X672278Y-303476D01*
X672638Y-303235D01*
X672998Y-303476D01*
X673622Y-303600D01*
X674246Y-303476D01*
X674606Y-303235D01*
X674966Y-303476D01*
X675591Y-303600D01*
X676215Y-303476D01*
X676744Y-303122D01*
X677098Y-302593D01*
X677222Y-301969D01*
X677098Y-301344D01*
X676744Y-300815D01*
X676564Y-300694D01*
Y-300093D01*
X676744Y-299972D01*
X677098Y-299443D01*
X677222Y-298819D01*
X677098Y-298195D01*
X676744Y-297665D01*
X676215Y-297312D01*
X675591Y-297188D01*
D02*
G37*
G36*
X588976Y-301125D02*
X588352Y-301249D01*
X587823Y-301602D01*
X587469Y-302132D01*
X587345Y-302756D01*
X587469Y-303380D01*
X587823Y-303909D01*
X588352Y-304263D01*
X588976Y-304387D01*
X589601Y-304263D01*
X590130Y-303909D01*
X590484Y-303380D01*
X590608Y-302756D01*
X590484Y-302132D01*
X590130Y-301602D01*
X589601Y-301249D01*
X588976Y-301125D01*
D02*
G37*
G36*
X579528Y-301518D02*
X578903Y-301642D01*
X578374Y-301996D01*
X578020Y-302525D01*
X577896Y-303150D01*
X578020Y-303774D01*
X578374Y-304303D01*
X578903Y-304657D01*
X579528Y-304781D01*
X580152Y-304657D01*
X580681Y-304303D01*
X581035Y-303774D01*
X581159Y-303150D01*
X581035Y-302525D01*
X580681Y-301996D01*
X580152Y-301642D01*
X579528Y-301518D01*
D02*
G37*
G36*
X453937Y-305110D02*
X453313Y-305235D01*
X452783Y-305588D01*
X452335D01*
X451805Y-305235D01*
X451181Y-305110D01*
X450557Y-305235D01*
X450028Y-305588D01*
X449907Y-305769D01*
X449306D01*
X449185Y-305588D01*
X448656Y-305235D01*
X448032Y-305110D01*
X447407Y-305235D01*
X446878Y-305588D01*
X446429D01*
X445900Y-305235D01*
X445276Y-305110D01*
X444651Y-305235D01*
X444122Y-305588D01*
X444001Y-305769D01*
X443400D01*
X443280Y-305588D01*
X442750Y-305235D01*
X442126Y-305110D01*
X441502Y-305235D01*
X440973Y-305588D01*
X440524D01*
X439994Y-305235D01*
X439370Y-305110D01*
X438746Y-305235D01*
X438217Y-305588D01*
X438096Y-305769D01*
X437495D01*
X437374Y-305588D01*
X436845Y-305235D01*
X436221Y-305110D01*
X435596Y-305235D01*
X435067Y-305588D01*
X434618D01*
X434089Y-305235D01*
X433465Y-305110D01*
X432840Y-305235D01*
X432311Y-305588D01*
X431957Y-306117D01*
X431833Y-306742D01*
X431957Y-307366D01*
X432311Y-307895D01*
X432840Y-308249D01*
X433465Y-308373D01*
X434089Y-308249D01*
X434618Y-307895D01*
X435067D01*
X435596Y-308249D01*
X436221Y-308373D01*
X436845Y-308249D01*
X437374Y-307895D01*
X437495Y-307715D01*
X438096D01*
X438217Y-307895D01*
X438746Y-308249D01*
X439370Y-308373D01*
X439994Y-308249D01*
X440524Y-307895D01*
X440973D01*
X441502Y-308249D01*
X442126Y-308373D01*
X442750Y-308249D01*
X443280Y-307895D01*
X443400Y-307715D01*
X444001D01*
X444122Y-307895D01*
X444651Y-308249D01*
X445276Y-308373D01*
X445900Y-308249D01*
X446429Y-307895D01*
X446878D01*
X447407Y-308249D01*
X448032Y-308373D01*
X448656Y-308249D01*
X449185Y-307895D01*
X449306Y-307715D01*
X449907D01*
X450028Y-307895D01*
X450557Y-308249D01*
X451181Y-308373D01*
X451805Y-308249D01*
X452335Y-307895D01*
X452783D01*
X453313Y-308249D01*
X453937Y-308373D01*
X454561Y-308249D01*
X455091Y-307895D01*
X455444Y-307366D01*
X455568Y-306742D01*
X455444Y-306117D01*
X455091Y-305588D01*
X454561Y-305235D01*
X453937Y-305110D01*
D02*
G37*
G36*
X470275Y-306678D02*
X469540Y-306824D01*
X468917Y-307240D01*
X468501Y-307863D01*
X468355Y-308597D01*
X468501Y-309332D01*
X468917Y-309955D01*
X469540Y-310371D01*
X470275Y-310517D01*
X471009Y-310371D01*
X471632Y-309955D01*
X472049Y-309332D01*
X472195Y-308597D01*
X472049Y-307863D01*
X471632Y-307240D01*
X471009Y-306824D01*
X470275Y-306678D01*
D02*
G37*
G36*
X391535D02*
X390800Y-306824D01*
X390177Y-307240D01*
X389761Y-307863D01*
X389615Y-308597D01*
X389761Y-309332D01*
X390177Y-309955D01*
X390800Y-310371D01*
X391535Y-310517D01*
X392269Y-310371D01*
X392892Y-309955D01*
X393309Y-309332D01*
X393455Y-308597D01*
X393309Y-307863D01*
X392892Y-307240D01*
X392269Y-306824D01*
X391535Y-306678D01*
D02*
G37*
G36*
X634252Y-312936D02*
X633628Y-313060D01*
X633098Y-313413D01*
X632745Y-313943D01*
X632621Y-314567D01*
X632745Y-315191D01*
X633098Y-315721D01*
X633628Y-316074D01*
X634252Y-316198D01*
X634876Y-316074D01*
X635405Y-315721D01*
X635759Y-315191D01*
X635883Y-314567D01*
X635759Y-313943D01*
X635405Y-313413D01*
X634876Y-313060D01*
X634252Y-312936D01*
D02*
G37*
G36*
X653150Y-312936D02*
X652525Y-313060D01*
X651996Y-313413D01*
X651642Y-313943D01*
X651518Y-314567D01*
X651642Y-315191D01*
X651996Y-315721D01*
X652525Y-316074D01*
X653150Y-316198D01*
X653774Y-316074D01*
X654303Y-315721D01*
X654657Y-315191D01*
X654781Y-314567D01*
X654657Y-313943D01*
X654303Y-313413D01*
X653774Y-313060D01*
X653150Y-312936D01*
D02*
G37*
G36*
X533015Y-306026D02*
X531701Y-306155D01*
X530437Y-306539D01*
X529272Y-307162D01*
X528251Y-308000D01*
X527413Y-309021D01*
X526790Y-310186D01*
X526407Y-311450D01*
X526277Y-312764D01*
X526407Y-314078D01*
X526790Y-315342D01*
X527413Y-316507D01*
X528251Y-317529D01*
X529272Y-318366D01*
X530437Y-318989D01*
X531701Y-319373D01*
X533015Y-319502D01*
X534330Y-319373D01*
X535594Y-318989D01*
X536759Y-318366D01*
X537780Y-317529D01*
X538618Y-316507D01*
X539240Y-315342D01*
X539624Y-314078D01*
X539753Y-312764D01*
X539624Y-311450D01*
X539240Y-310186D01*
X538618Y-309021D01*
X537780Y-308000D01*
X536759Y-307162D01*
X535594Y-306539D01*
X534330Y-306155D01*
X533015Y-306026D01*
D02*
G37*
G36*
X336515D02*
X335201Y-306155D01*
X333937Y-306539D01*
X332772Y-307162D01*
X331751Y-308000D01*
X330913Y-309021D01*
X330290Y-310186D01*
X329907Y-311450D01*
X329777Y-312764D01*
X329907Y-314078D01*
X330290Y-315342D01*
X330913Y-316507D01*
X331751Y-317529D01*
X332772Y-318366D01*
X333937Y-318989D01*
X335201Y-319373D01*
X336515Y-319502D01*
X337830Y-319373D01*
X339094Y-318989D01*
X340259Y-318366D01*
X341280Y-317529D01*
X342118Y-316507D01*
X342740Y-315342D01*
X343124Y-314078D01*
X343253Y-312764D01*
X343124Y-311450D01*
X342740Y-310186D01*
X342118Y-309021D01*
X341280Y-308000D01*
X340259Y-307162D01*
X339094Y-306539D01*
X337830Y-306155D01*
X336515Y-306026D01*
D02*
G37*
G36*
X142520Y-311946D02*
X141332Y-312103D01*
X140225Y-312561D01*
X139275Y-313290D01*
X138545Y-314241D01*
X138087Y-315348D01*
X137930Y-316535D01*
X138087Y-317723D01*
X138545Y-318830D01*
X139275Y-319780D01*
X140225Y-320510D01*
X141332Y-320968D01*
X142520Y-321125D01*
X143708Y-320968D01*
X144814Y-320510D01*
X145765Y-319780D01*
X146494Y-318830D01*
X146953Y-317723D01*
X147109Y-316535D01*
X146953Y-315348D01*
X146494Y-314241D01*
X145765Y-313290D01*
X144814Y-312561D01*
X143708Y-312103D01*
X142520Y-311946D01*
D02*
G37*
G36*
X-3728Y-312044D02*
X-13202D01*
Y-321518D01*
X-3728D01*
Y-312044D01*
D02*
G37*
G36*
X85416Y-316068D02*
X84791Y-316192D01*
X84262Y-316546D01*
X83908Y-317075D01*
X83784Y-317699D01*
X83908Y-318323D01*
X84262Y-318853D01*
X84274Y-319462D01*
X84123Y-319689D01*
X83999Y-320313D01*
X84123Y-320938D01*
X84476Y-321467D01*
X85006Y-321821D01*
X85630Y-321945D01*
X86254Y-321821D01*
X86783Y-321467D01*
X87137Y-320938D01*
X87261Y-320313D01*
X87137Y-319689D01*
X86783Y-319160D01*
X86771Y-318550D01*
X86923Y-318323D01*
X87047Y-317699D01*
X86923Y-317075D01*
X86569Y-316546D01*
X86040Y-316192D01*
X85416Y-316068D01*
D02*
G37*
G36*
X447244Y-323221D02*
X446620Y-323345D01*
X446091Y-323698D01*
X445642D01*
X445113Y-323345D01*
X444488Y-323221D01*
X443864Y-323345D01*
X443335Y-323698D01*
X442981Y-324228D01*
X442857Y-324852D01*
X442981Y-325476D01*
X443335Y-326006D01*
X443864Y-326359D01*
X444488Y-326483D01*
X445113Y-326359D01*
X445642Y-326006D01*
X446091D01*
X446620Y-326359D01*
X447244Y-326483D01*
X447868Y-326359D01*
X448398Y-326006D01*
X448751Y-325476D01*
X448876Y-324852D01*
X448751Y-324228D01*
X448398Y-323698D01*
X447868Y-323345D01*
X447244Y-323221D01*
D02*
G37*
G36*
X440551D02*
X439927Y-323345D01*
X439398Y-323698D01*
X438949D01*
X438420Y-323345D01*
X437795Y-323221D01*
X437171Y-323345D01*
X436642Y-323698D01*
X436288Y-324228D01*
X436164Y-324852D01*
X436288Y-325476D01*
X436642Y-326006D01*
X437171Y-326359D01*
X437795Y-326483D01*
X438420Y-326359D01*
X438949Y-326006D01*
X439398D01*
X439927Y-326359D01*
X440551Y-326483D01*
X441176Y-326359D01*
X441705Y-326006D01*
X442058Y-325476D01*
X442182Y-324852D01*
X442058Y-324228D01*
X441705Y-323698D01*
X441176Y-323345D01*
X440551Y-323221D01*
D02*
G37*
G36*
X433858D02*
X433234Y-323345D01*
X432705Y-323698D01*
X432256D01*
X431727Y-323345D01*
X431102Y-323221D01*
X430478Y-323345D01*
X429949Y-323698D01*
X429595Y-324228D01*
X429471Y-324852D01*
X429595Y-325476D01*
X429949Y-326006D01*
X430478Y-326359D01*
X431102Y-326483D01*
X431727Y-326359D01*
X432256Y-326006D01*
X432705D01*
X433234Y-326359D01*
X433858Y-326483D01*
X434483Y-326359D01*
X435012Y-326006D01*
X435365Y-325476D01*
X435490Y-324852D01*
X435365Y-324228D01*
X435012Y-323698D01*
X434483Y-323345D01*
X433858Y-323221D01*
D02*
G37*
G36*
X460630D02*
X460006Y-323345D01*
X459476Y-323698D01*
X459356Y-323879D01*
X458754D01*
X458634Y-323698D01*
X458105Y-323345D01*
X457480Y-323221D01*
X456856Y-323345D01*
X456327Y-323698D01*
X455973Y-324228D01*
X455964Y-324276D01*
X455454D01*
X455444Y-324228D01*
X455091Y-323698D01*
X454561Y-323345D01*
X453937Y-323221D01*
X453313Y-323345D01*
X452783Y-323698D01*
X452335D01*
X451805Y-323345D01*
X451181Y-323221D01*
X450557Y-323345D01*
X450028Y-323698D01*
X449674Y-324228D01*
X449550Y-324852D01*
X449674Y-325476D01*
X450028Y-326006D01*
X450557Y-326359D01*
X451181Y-326483D01*
X451805Y-326359D01*
X452335Y-326006D01*
X452783D01*
X453313Y-326359D01*
X453937Y-326483D01*
X454561Y-326359D01*
X455091Y-326006D01*
X455444Y-325476D01*
X455454Y-325428D01*
X455964D01*
X455973Y-325476D01*
X456327Y-326006D01*
X456856Y-326359D01*
X457480Y-326483D01*
X458105Y-326359D01*
X458634Y-326006D01*
X458754Y-325825D01*
X459356D01*
X459476Y-326006D01*
X460006Y-326359D01*
X460630Y-326483D01*
X461254Y-326359D01*
X461784Y-326006D01*
X462137Y-325476D01*
X462261Y-324852D01*
X462137Y-324228D01*
X461784Y-323698D01*
X461254Y-323345D01*
X460630Y-323221D01*
D02*
G37*
G36*
X87598Y-328093D02*
X86974Y-328217D01*
X86445Y-328571D01*
X86091Y-329100D01*
X85967Y-329724D01*
X86091Y-330349D01*
X86445Y-330878D01*
X86974Y-331232D01*
X87598Y-331356D01*
X88223Y-331232D01*
X88752Y-330878D01*
X89106Y-330349D01*
X89230Y-329724D01*
X89106Y-329100D01*
X88752Y-328571D01*
X88223Y-328217D01*
X87598Y-328093D01*
D02*
G37*
G36*
X62992D02*
X62368Y-328217D01*
X61839Y-328571D01*
X61485Y-329100D01*
X61361Y-329724D01*
X61485Y-330349D01*
X61839Y-330878D01*
X62368Y-331232D01*
X62992Y-331356D01*
X63616Y-331232D01*
X64146Y-330878D01*
X64499Y-330349D01*
X64623Y-329724D01*
X64499Y-329100D01*
X64146Y-328571D01*
X63616Y-328217D01*
X62992Y-328093D01*
D02*
G37*
G36*
X294094Y-322576D02*
X292907Y-322732D01*
X291800Y-323191D01*
X290849Y-323920D01*
X290120Y-324871D01*
X289662Y-325978D01*
X289505Y-327165D01*
X289662Y-328353D01*
X290120Y-329460D01*
X290849Y-330410D01*
X291800Y-331140D01*
X292907Y-331598D01*
X294094Y-331755D01*
X295282Y-331598D01*
X296389Y-331140D01*
X297340Y-330410D01*
X298069Y-329460D01*
X298527Y-328353D01*
X298684Y-327165D01*
X298527Y-325978D01*
X298069Y-324871D01*
X297340Y-323920D01*
X296389Y-323191D01*
X295282Y-322732D01*
X294094Y-322576D01*
D02*
G37*
G36*
X282283D02*
X281096Y-322732D01*
X279989Y-323191D01*
X279038Y-323920D01*
X278309Y-324871D01*
X277851Y-325978D01*
X277694Y-327165D01*
X277851Y-328353D01*
X278309Y-329460D01*
X279038Y-330410D01*
X279989Y-331140D01*
X281096Y-331598D01*
X282283Y-331755D01*
X283471Y-331598D01*
X284578Y-331140D01*
X285529Y-330410D01*
X286258Y-329460D01*
X286716Y-328353D01*
X286873Y-327165D01*
X286716Y-325978D01*
X286258Y-324871D01*
X285529Y-323920D01*
X284578Y-323191D01*
X283471Y-322732D01*
X282283Y-322576D01*
D02*
G37*
G36*
X270472D02*
X269285Y-322732D01*
X268178Y-323191D01*
X267227Y-323920D01*
X266498Y-324871D01*
X266040Y-325978D01*
X265883Y-327165D01*
X266040Y-328353D01*
X266498Y-329460D01*
X267227Y-330410D01*
X268178Y-331140D01*
X269285Y-331598D01*
X270472Y-331755D01*
X271660Y-331598D01*
X272767Y-331140D01*
X273717Y-330410D01*
X274447Y-329460D01*
X274905Y-328353D01*
X275062Y-327165D01*
X274905Y-325978D01*
X274447Y-324871D01*
X273717Y-323920D01*
X272767Y-323191D01*
X271660Y-322732D01*
X270472Y-322576D01*
D02*
G37*
G36*
X258472D02*
X257285Y-322732D01*
X256178Y-323191D01*
X255227Y-323920D01*
X254498Y-324871D01*
X254040Y-325978D01*
X253883Y-327165D01*
X254040Y-328353D01*
X254498Y-329460D01*
X255227Y-330410D01*
X256178Y-331140D01*
X257285Y-331598D01*
X258472Y-331755D01*
X259660Y-331598D01*
X260767Y-331140D01*
X261718Y-330410D01*
X262447Y-329460D01*
X262905Y-328353D01*
X263062Y-327165D01*
X262905Y-325978D01*
X262447Y-324871D01*
X261718Y-323920D01*
X260767Y-323191D01*
X259660Y-322732D01*
X258472Y-322576D01*
D02*
G37*
G36*
X246472D02*
X245285Y-322732D01*
X244178Y-323191D01*
X243227Y-323920D01*
X242498Y-324871D01*
X242040Y-325978D01*
X241883Y-327165D01*
X242040Y-328353D01*
X242498Y-329460D01*
X243227Y-330410D01*
X244178Y-331140D01*
X245285Y-331598D01*
X246472Y-331755D01*
X247660Y-331598D01*
X248767Y-331140D01*
X249717Y-330410D01*
X250447Y-329460D01*
X250905Y-328353D01*
X251062Y-327165D01*
X250905Y-325978D01*
X250447Y-324871D01*
X249717Y-323920D01*
X248767Y-323191D01*
X247660Y-322732D01*
X246472Y-322576D01*
D02*
G37*
G36*
X604291Y-325905D02*
X603221Y-326046D01*
X602224Y-326459D01*
X601368Y-327116D01*
X600711Y-327972D01*
X600298Y-328969D01*
X600157Y-330039D01*
X600298Y-331109D01*
X600711Y-332107D01*
X601368Y-332963D01*
X602224Y-333620D01*
X603221Y-334033D01*
X604291Y-334174D01*
X605361Y-334033D01*
X606359Y-333620D01*
X607215Y-332963D01*
X607872Y-332107D01*
X608285Y-331109D01*
X608426Y-330039D01*
X608285Y-328969D01*
X607872Y-327972D01*
X607215Y-327116D01*
X606359Y-326459D01*
X605361Y-326046D01*
X604291Y-325905D01*
D02*
G37*
G36*
X574291D02*
X573221Y-326046D01*
X572224Y-326459D01*
X571368Y-327116D01*
X570711Y-327972D01*
X570298Y-328969D01*
X570157Y-330039D01*
X570298Y-331109D01*
X570711Y-332107D01*
X571368Y-332963D01*
X572224Y-333620D01*
X573221Y-334033D01*
X574291Y-334174D01*
X575361Y-334033D01*
X576359Y-333620D01*
X577215Y-332963D01*
X577872Y-332107D01*
X578285Y-331109D01*
X578426Y-330039D01*
X578285Y-328969D01*
X577872Y-327972D01*
X577215Y-327116D01*
X576359Y-326459D01*
X575361Y-326046D01*
X574291Y-325905D01*
D02*
G37*
G36*
X87598Y-333999D02*
X86974Y-334123D01*
X86445Y-334476D01*
X86091Y-335006D01*
X85967Y-335630D01*
X86091Y-336254D01*
X86445Y-336784D01*
X86974Y-337137D01*
X87598Y-337261D01*
X88223Y-337137D01*
X88752Y-336784D01*
X89106Y-336254D01*
X89230Y-335630D01*
X89106Y-335006D01*
X88752Y-334476D01*
X88223Y-334123D01*
X87598Y-333999D01*
D02*
G37*
G36*
X-23622D02*
X-24246Y-334123D01*
X-24776Y-334476D01*
X-25129Y-335006D01*
X-25253Y-335630D01*
X-25129Y-336254D01*
X-24776Y-336784D01*
X-24246Y-337137D01*
X-23622Y-337261D01*
X-22998Y-337137D01*
X-22468Y-336784D01*
X-22115Y-336254D01*
X-21991Y-335630D01*
X-22115Y-335006D01*
X-22468Y-334476D01*
X-22998Y-334123D01*
X-23622Y-333999D01*
D02*
G37*
G36*
X508997Y-334044D02*
X508373Y-334168D01*
X507843Y-334521D01*
X507490Y-335051D01*
X507366Y-335675D01*
X507490Y-336299D01*
X507843Y-336828D01*
X508373Y-337182D01*
X508997Y-337306D01*
X509621Y-337182D01*
X510151Y-336828D01*
X510504Y-336299D01*
X510628Y-335675D01*
X510504Y-335051D01*
X510151Y-334521D01*
X509621Y-334168D01*
X508997Y-334044D01*
D02*
G37*
G36*
X74803Y-337936D02*
X74179Y-338060D01*
X73650Y-338413D01*
X73296Y-338943D01*
X73172Y-339567D01*
X73296Y-340191D01*
X73650Y-340721D01*
X74179Y-341074D01*
X74803Y-341198D01*
X75427Y-341074D01*
X75957Y-340721D01*
X76310Y-340191D01*
X76434Y-339567D01*
X76310Y-338943D01*
X75957Y-338413D01*
X75427Y-338060D01*
X74803Y-337936D01*
D02*
G37*
G36*
X78740Y-338920D02*
X78116Y-339044D01*
X77587Y-339398D01*
X77233Y-339927D01*
X77109Y-340551D01*
X77233Y-341176D01*
X77587Y-341705D01*
X78116Y-342058D01*
X78740Y-342182D01*
X79364Y-342058D01*
X79894Y-341705D01*
X80247Y-341176D01*
X80371Y-340551D01*
X80247Y-339927D01*
X79894Y-339398D01*
X79364Y-339044D01*
X78740Y-338920D01*
D02*
G37*
G36*
X-23622Y-337936D02*
X-24246Y-338060D01*
X-24776Y-338413D01*
X-25129Y-338943D01*
X-25253Y-339567D01*
X-25129Y-340191D01*
X-24776Y-340721D01*
X-24667Y-340793D01*
Y-341293D01*
X-24776Y-341366D01*
X-25129Y-341895D01*
X-25253Y-342520D01*
X-25129Y-343144D01*
X-24776Y-343673D01*
X-24246Y-344027D01*
X-23622Y-344151D01*
X-22998Y-344027D01*
X-22468Y-343673D01*
X-22115Y-343144D01*
X-21991Y-342520D01*
X-22115Y-341895D01*
X-22468Y-341366D01*
X-22578Y-341293D01*
Y-340793D01*
X-22468Y-340721D01*
X-22115Y-340191D01*
X-21991Y-339567D01*
X-22115Y-338943D01*
X-22468Y-338413D01*
X-22998Y-338060D01*
X-23622Y-337936D01*
D02*
G37*
G36*
Y-344825D02*
X-24246Y-344950D01*
X-24776Y-345303D01*
X-25129Y-345832D01*
X-25253Y-346457D01*
X-25129Y-347081D01*
X-24776Y-347610D01*
X-24246Y-347964D01*
X-23622Y-348088D01*
X-22998Y-347964D01*
X-22468Y-347610D01*
X-22115Y-347081D01*
X-21991Y-346457D01*
X-22115Y-345832D01*
X-22468Y-345303D01*
X-22998Y-344950D01*
X-23622Y-344825D01*
D02*
G37*
G36*
X509391Y-349004D02*
X508767Y-349128D01*
X508237Y-349482D01*
X507884Y-350011D01*
X507759Y-350636D01*
X507884Y-351260D01*
X508237Y-351789D01*
X508767Y-352143D01*
X509391Y-352267D01*
X510015Y-352143D01*
X510544Y-351789D01*
X510898Y-351260D01*
X511022Y-350636D01*
X510898Y-350011D01*
X510544Y-349482D01*
X510015Y-349128D01*
X509391Y-349004D01*
D02*
G37*
G36*
X486221Y-327210D02*
X484133Y-327374D01*
X482098Y-327863D01*
X480164Y-328664D01*
X478379Y-329758D01*
X476787Y-331118D01*
X475427Y-332710D01*
X474333Y-334494D01*
X473532Y-336428D01*
X473044Y-338464D01*
X472879Y-340551D01*
X473044Y-342638D01*
X473532Y-344674D01*
X474333Y-346608D01*
X475427Y-348393D01*
X476787Y-349985D01*
X478379Y-351344D01*
X480164Y-352438D01*
X482098Y-353239D01*
X484133Y-353728D01*
X486221Y-353892D01*
X488308Y-353728D01*
X490343Y-353239D01*
X492277Y-352438D01*
X494062Y-351344D01*
X495654Y-349985D01*
X497014Y-348393D01*
X498107Y-346608D01*
X498909Y-344674D01*
X499397Y-342638D01*
X499562Y-340551D01*
X499397Y-338464D01*
X498909Y-336428D01*
X498107Y-334494D01*
X497014Y-332710D01*
X495654Y-331118D01*
X494062Y-329758D01*
X492277Y-328664D01*
X490343Y-327863D01*
X488308Y-327374D01*
X486221Y-327210D01*
D02*
G37*
G36*
X685039Y-327210D02*
X682952Y-327374D01*
X680917Y-327863D01*
X678983Y-328664D01*
X677198Y-329758D01*
X675606Y-331118D01*
X674246Y-332710D01*
X673152Y-334494D01*
X672351Y-336429D01*
X671863Y-338464D01*
X671698Y-340551D01*
X671863Y-342638D01*
X672351Y-344674D01*
X673152Y-346608D01*
X674246Y-348393D01*
X675606Y-349985D01*
X677198Y-351344D01*
X678983Y-352438D01*
X680917Y-353239D01*
X682952Y-353728D01*
X685039Y-353892D01*
X687126Y-353728D01*
X689162Y-353239D01*
X691096Y-352438D01*
X692881Y-351344D01*
X694473Y-349985D01*
X695833Y-348393D01*
X696926Y-346608D01*
X697727Y-344674D01*
X698216Y-342638D01*
X698381Y-340551D01*
X698216Y-338464D01*
X697727Y-336429D01*
X696926Y-334494D01*
X695833Y-332710D01*
X694473Y-331118D01*
X692881Y-329758D01*
X691096Y-328664D01*
X689162Y-327863D01*
X687126Y-327374D01*
X685039Y-327210D01*
D02*
G37*
G36*
X157480Y-357030D02*
X156856Y-357154D01*
X156496Y-357395D01*
X156136Y-357154D01*
X155512Y-357030D01*
X154887Y-357154D01*
X154528Y-357395D01*
X154168Y-357154D01*
X153543Y-357030D01*
X152919Y-357154D01*
X152390Y-357508D01*
X152036Y-358037D01*
X151912Y-358661D01*
X152036Y-359286D01*
X152390Y-359815D01*
X152570Y-359936D01*
Y-360537D01*
X152390Y-360658D01*
X152036Y-361187D01*
X151912Y-361811D01*
X152036Y-362435D01*
X152390Y-362965D01*
X152919Y-363318D01*
X153543Y-363442D01*
X154168Y-363318D01*
X154528Y-363078D01*
X154887Y-363318D01*
X155512Y-363442D01*
X156136Y-363318D01*
X156496Y-363078D01*
X156856Y-363318D01*
X157480Y-363442D01*
X158105Y-363318D01*
X158634Y-362965D01*
X158987Y-362435D01*
X159112Y-361811D01*
X158987Y-361187D01*
X158634Y-360658D01*
X158453Y-360537D01*
Y-359936D01*
X158634Y-359815D01*
X158987Y-359286D01*
X159112Y-358661D01*
X158987Y-358037D01*
X158634Y-357508D01*
X158105Y-357154D01*
X157480Y-357030D01*
D02*
G37*
G36*
X218445Y-372476D02*
X217821Y-372600D01*
X217291Y-372954D01*
X216938Y-373483D01*
X216814Y-374108D01*
X216938Y-374732D01*
X217291Y-375261D01*
X217821Y-375615D01*
X218445Y-375739D01*
X219069Y-375615D01*
X219599Y-375261D01*
X219952Y-374732D01*
X220076Y-374108D01*
X219952Y-373483D01*
X219599Y-372954D01*
X219069Y-372600D01*
X218445Y-372476D01*
D02*
G37*
G36*
X269502Y-372660D02*
X268878Y-372784D01*
X268349Y-373137D01*
X267995Y-373667D01*
X267871Y-374291D01*
X267995Y-374915D01*
X268349Y-375445D01*
X268878Y-375798D01*
X269502Y-375922D01*
X270127Y-375798D01*
X270656Y-375445D01*
X271010Y-374915D01*
X271134Y-374291D01*
X271010Y-373667D01*
X270656Y-373137D01*
X270127Y-372784D01*
X269502Y-372660D01*
D02*
G37*
G36*
X273425Y-373024D02*
X272801Y-373148D01*
X272272Y-373502D01*
X271918Y-374031D01*
X271794Y-374655D01*
X271918Y-375279D01*
X272272Y-375809D01*
X272801Y-376162D01*
X273425Y-376287D01*
X274049Y-376162D01*
X274579Y-375809D01*
X274932Y-375279D01*
X275057Y-374655D01*
X274932Y-374031D01*
X274579Y-373502D01*
X274049Y-373148D01*
X273425Y-373024D01*
D02*
G37*
G36*
X253655Y-372790D02*
X253031Y-372914D01*
X252502Y-373268D01*
X252148Y-373797D01*
X252024Y-374421D01*
X252148Y-375045D01*
X252502Y-375575D01*
X253031Y-375928D01*
X253655Y-376052D01*
X254279Y-375928D01*
X254809Y-375575D01*
X254916Y-375413D01*
X254985Y-375394D01*
X255495Y-375448D01*
X255736Y-375809D01*
X256265Y-376162D01*
X256890Y-376287D01*
X257514Y-376162D01*
X258043Y-375809D01*
X258397Y-375279D01*
X258521Y-374655D01*
X258397Y-374031D01*
X258043Y-373502D01*
X257514Y-373148D01*
X256890Y-373024D01*
X256265Y-373148D01*
X255736Y-373502D01*
X255628Y-373663D01*
X255560Y-373683D01*
X255050Y-373629D01*
X254809Y-373268D01*
X254279Y-372914D01*
X253655Y-372790D01*
D02*
G37*
G36*
X241929Y-373024D02*
X241305Y-373148D01*
X240776Y-373502D01*
X240422Y-374031D01*
X240298Y-374655D01*
X240422Y-375279D01*
X240776Y-375809D01*
X241305Y-376162D01*
X241929Y-376287D01*
X242553Y-376162D01*
X243083Y-375809D01*
X243436Y-375279D01*
X243561Y-374655D01*
X243436Y-374031D01*
X243083Y-373502D01*
X242553Y-373148D01*
X241929Y-373024D01*
D02*
G37*
G36*
X237992D02*
X237368Y-373148D01*
X236839Y-373502D01*
X236485Y-374031D01*
X236361Y-374655D01*
X236485Y-375279D01*
X236839Y-375809D01*
X237368Y-376162D01*
X237992Y-376287D01*
X238616Y-376162D01*
X239146Y-375809D01*
X239499Y-375279D01*
X239623Y-374655D01*
X239499Y-374031D01*
X239146Y-373502D01*
X238616Y-373148D01*
X237992Y-373024D01*
D02*
G37*
G36*
X222638D02*
X222013Y-373148D01*
X221484Y-373502D01*
X221131Y-374031D01*
X221006Y-374655D01*
X221131Y-375279D01*
X221484Y-375809D01*
X222013Y-376162D01*
X222638Y-376287D01*
X223262Y-376162D01*
X223791Y-375809D01*
X224145Y-375279D01*
X224269Y-374655D01*
X224145Y-374031D01*
X223791Y-373502D01*
X223262Y-373148D01*
X222638Y-373024D01*
D02*
G37*
G36*
X210433D02*
X209809Y-373148D01*
X209279Y-373502D01*
X208926Y-374031D01*
X208802Y-374655D01*
X208926Y-375279D01*
X209279Y-375809D01*
X209809Y-376162D01*
X210433Y-376287D01*
X211057Y-376162D01*
X211587Y-375809D01*
X211940Y-375279D01*
X212064Y-374655D01*
X211940Y-374031D01*
X211587Y-373502D01*
X211057Y-373148D01*
X210433Y-373024D01*
D02*
G37*
G36*
X206496D02*
X205872Y-373148D01*
X205343Y-373502D01*
X204989Y-374031D01*
X204865Y-374655D01*
X204989Y-375279D01*
X205343Y-375809D01*
X205872Y-376162D01*
X206496Y-376287D01*
X207120Y-376162D01*
X207650Y-375809D01*
X208003Y-375279D01*
X208127Y-374655D01*
X208003Y-374031D01*
X207650Y-373502D01*
X207120Y-373148D01*
X206496Y-373024D01*
D02*
G37*
G36*
X190354Y-375780D02*
X189730Y-375904D01*
X189201Y-376257D01*
X188847Y-376787D01*
X188723Y-377411D01*
X188847Y-378035D01*
X189201Y-378565D01*
X189730Y-378918D01*
X190354Y-379042D01*
X190979Y-378918D01*
X191508Y-378565D01*
X191861Y-378035D01*
X191986Y-377411D01*
X191861Y-376787D01*
X191508Y-376257D01*
X190979Y-375904D01*
X190354Y-375780D01*
D02*
G37*
G36*
X178543D02*
X177919Y-375904D01*
X177390Y-376257D01*
X177036Y-376787D01*
X176912Y-377411D01*
X177036Y-378035D01*
X177390Y-378565D01*
X177919Y-378918D01*
X178543Y-379042D01*
X179168Y-378918D01*
X179697Y-378565D01*
X180051Y-378035D01*
X180175Y-377411D01*
X180051Y-376787D01*
X179697Y-376257D01*
X179168Y-375904D01*
X178543Y-375780D01*
D02*
G37*
G36*
X158661Y-384835D02*
X158037Y-384959D01*
X157677Y-385199D01*
X157317Y-384959D01*
X156693Y-384835D01*
X156069Y-384959D01*
X155709Y-385199D01*
X155349Y-384959D01*
X154724Y-384835D01*
X154100Y-384959D01*
X153571Y-385313D01*
X153217Y-385842D01*
X153093Y-386466D01*
X153217Y-387090D01*
X153571Y-387620D01*
X153751Y-387740D01*
Y-388342D01*
X153571Y-388462D01*
X153217Y-388991D01*
X153093Y-389616D01*
X153217Y-390240D01*
X153571Y-390769D01*
X154100Y-391123D01*
X154724Y-391247D01*
X155349Y-391123D01*
X155709Y-390882D01*
X156069Y-391123D01*
X156693Y-391247D01*
X157317Y-391123D01*
X157677Y-390882D01*
X158037Y-391123D01*
X158661Y-391247D01*
X159286Y-391123D01*
X159815Y-390769D01*
X160169Y-390240D01*
X160293Y-389616D01*
X160169Y-388991D01*
X159815Y-388462D01*
X159634Y-388342D01*
Y-387740D01*
X159815Y-387620D01*
X160169Y-387090D01*
X160293Y-386466D01*
X160169Y-385842D01*
X159815Y-385313D01*
X159286Y-384959D01*
X158661Y-384835D01*
D02*
G37*
G36*
X182677D02*
X182053Y-384959D01*
X181524Y-385313D01*
X181170Y-385842D01*
X181160Y-385890D01*
X180651D01*
X180641Y-385842D01*
X180287Y-385313D01*
X179758Y-384959D01*
X179134Y-384835D01*
X178510Y-384959D01*
X177980Y-385313D01*
X177627Y-385842D01*
X177503Y-386466D01*
X177627Y-387090D01*
X177980Y-387620D01*
X178161Y-387740D01*
Y-388342D01*
X177980Y-388462D01*
X177627Y-388991D01*
X177503Y-389616D01*
X177627Y-390240D01*
X177980Y-390769D01*
X178510Y-391123D01*
X179134Y-391247D01*
X179758Y-391123D01*
X180287Y-390769D01*
X180641Y-390240D01*
X180651Y-390192D01*
X181160D01*
X181170Y-390240D01*
X181524Y-390769D01*
X182053Y-391123D01*
X182677Y-391247D01*
X183301Y-391123D01*
X183831Y-390769D01*
X184184Y-390240D01*
X184309Y-389616D01*
X184184Y-388991D01*
X183831Y-388462D01*
X183650Y-388342D01*
Y-387740D01*
X183831Y-387620D01*
X184184Y-387090D01*
X184309Y-386466D01*
X184184Y-385842D01*
X183831Y-385313D01*
X183301Y-384959D01*
X182677Y-384835D01*
D02*
G37*
G36*
X232480Y-385622D02*
X231856Y-385746D01*
X231327Y-386100D01*
X231206Y-386280D01*
X230605D01*
X230484Y-386100D01*
X229955Y-385746D01*
X229331Y-385622D01*
X228706Y-385746D01*
X228177Y-386100D01*
X227823Y-386629D01*
X227699Y-387253D01*
X227823Y-387878D01*
X228177Y-388407D01*
X228706Y-388761D01*
X229331Y-388885D01*
X229955Y-388761D01*
X230484Y-388407D01*
X230605Y-388227D01*
X231206D01*
X231327Y-388407D01*
X231856Y-388761D01*
X232480Y-388885D01*
X233105Y-388761D01*
X233634Y-388407D01*
X233987Y-387878D01*
X234112Y-387253D01*
X233987Y-386629D01*
X233634Y-386100D01*
X233105Y-385746D01*
X232480Y-385622D01*
D02*
G37*
G36*
X215945D02*
X215321Y-385746D01*
X214791Y-386100D01*
X214671Y-386280D01*
X214069D01*
X213949Y-386100D01*
X213420Y-385746D01*
X212795Y-385622D01*
X212171Y-385746D01*
X211642Y-386100D01*
X211288Y-386629D01*
X211164Y-387253D01*
X211288Y-387878D01*
X211642Y-388407D01*
X212171Y-388761D01*
X212795Y-388885D01*
X213420Y-388761D01*
X213949Y-388407D01*
X214069Y-388227D01*
X214671D01*
X214791Y-388407D01*
X215321Y-388761D01*
X215945Y-388885D01*
X216569Y-388761D01*
X217098Y-388407D01*
X217452Y-387878D01*
X217576Y-387253D01*
X217452Y-386629D01*
X217098Y-386100D01*
X216569Y-385746D01*
X215945Y-385622D01*
D02*
G37*
G36*
X265158D02*
X264533Y-385746D01*
X264004Y-386100D01*
X263882Y-386283D01*
X263281D01*
X263160Y-386102D01*
X262631Y-385748D01*
X262006Y-385624D01*
X261382Y-385748D01*
X260853Y-386102D01*
X260499Y-386631D01*
X260375Y-387255D01*
X260499Y-387880D01*
X260853Y-388409D01*
X261382Y-388762D01*
X262006Y-388887D01*
X262631Y-388762D01*
X263160Y-388409D01*
X263282Y-388226D01*
X263883D01*
X264004Y-388407D01*
X264533Y-388761D01*
X265158Y-388885D01*
X265782Y-388761D01*
X266311Y-388407D01*
X266665Y-387878D01*
X266789Y-387253D01*
X266665Y-386629D01*
X266311Y-386100D01*
X265782Y-385746D01*
X265158Y-385622D01*
D02*
G37*
G36*
X246339Y-385344D02*
X245714Y-385468D01*
X245185Y-385822D01*
X244831Y-386351D01*
X244707Y-386975D01*
X244831Y-387599D01*
X245185Y-388129D01*
X245714Y-388482D01*
X246339Y-388606D01*
X246963Y-388482D01*
X247492Y-388129D01*
X248082Y-388146D01*
X248256Y-388407D01*
X248785Y-388761D01*
X249410Y-388885D01*
X250034Y-388761D01*
X250563Y-388407D01*
X250917Y-387878D01*
X251041Y-387253D01*
X250917Y-386629D01*
X250563Y-386100D01*
X250034Y-385746D01*
X249410Y-385622D01*
X248785Y-385746D01*
X248256Y-386100D01*
X247666Y-386082D01*
X247492Y-385822D01*
X246963Y-385468D01*
X246339Y-385344D01*
D02*
G37*
G36*
X186614Y-384835D02*
X185990Y-384959D01*
X185461Y-385313D01*
X185107Y-385842D01*
X184983Y-386466D01*
X185107Y-387090D01*
X185461Y-387620D01*
X185641Y-387740D01*
Y-388342D01*
X185461Y-388462D01*
X185107Y-388991D01*
X184983Y-389616D01*
X185107Y-390240D01*
X185461Y-390769D01*
X185990Y-391123D01*
X186614Y-391247D01*
X187239Y-391123D01*
X187768Y-390769D01*
X188121Y-390240D01*
X188245Y-389616D01*
X188121Y-388991D01*
X187768Y-388462D01*
X187587Y-388342D01*
Y-387740D01*
X187768Y-387620D01*
X188121Y-387090D01*
X188245Y-386466D01*
X188121Y-385842D01*
X187768Y-385313D01*
X187239Y-384959D01*
X186614Y-384835D01*
D02*
G37*
G36*
X0Y-365054D02*
X-2087Y-365218D01*
X-4123Y-365707D01*
X-6057Y-366508D01*
X-7842Y-367602D01*
X-9434Y-368962D01*
X-10793Y-370554D01*
X-11887Y-372339D01*
X-12688Y-374273D01*
X-13177Y-376308D01*
X-13341Y-378395D01*
X-13177Y-380482D01*
X-12688Y-382518D01*
X-11887Y-384452D01*
X-10793Y-386237D01*
X-9434Y-387829D01*
X-7842Y-389189D01*
X-6057Y-390282D01*
X-4123Y-391083D01*
X-2087Y-391572D01*
X0Y-391736D01*
X2087Y-391572D01*
X4123Y-391083D01*
X6057Y-390282D01*
X7842Y-389189D01*
X9434Y-387829D01*
X10793Y-386237D01*
X11887Y-384452D01*
X12688Y-382518D01*
X13177Y-380482D01*
X13341Y-378395D01*
X13177Y-376308D01*
X12688Y-374273D01*
X11887Y-372339D01*
X10793Y-370554D01*
X9434Y-368962D01*
X7842Y-367602D01*
X6057Y-366508D01*
X4123Y-365707D01*
X2087Y-365218D01*
X0Y-365054D01*
D02*
G37*
%LPD*%
D157*
X162362Y-120079D02*
D03*
X549055Y13937D02*
D03*
Y3937D02*
D03*
D159*
X302362Y-316535D02*
D03*
X142520Y-236614D02*
D03*
D160*
X348211Y-89891D02*
D03*
X357798Y-89963D02*
D03*
D161*
X624016Y-194488D02*
D03*
Y-177953D02*
D03*
Y-161417D02*
D03*
D164*
X-18464Y-326781D02*
D03*
X1535D02*
D03*
Y-306781D02*
D03*
X-18464D02*
D03*
X-18465Y-273630D02*
D03*
X1535D02*
D03*
Y-253630D02*
D03*
X-18465D02*
D03*
Y-220480D02*
D03*
X1535D02*
D03*
Y-200480D02*
D03*
X-18465D02*
D03*
X-18464Y-167332D02*
D03*
X1535D02*
D03*
Y-147332D02*
D03*
X-18464D02*
D03*
D167*
X315097Y-235081D02*
D03*
X287941Y-241819D02*
D03*
X288189Y-235827D02*
D03*
X615748Y-305512D02*
D03*
X562598Y-306693D02*
D03*
X600000Y-146063D02*
D03*
X598032D02*
D03*
X596063D02*
D03*
X587008D02*
D03*
X585039D02*
D03*
X583071D02*
D03*
X575984Y-145669D02*
D03*
X574016D02*
D03*
X572047D02*
D03*
X650787Y-229921D02*
D03*
X645669Y-230315D02*
D03*
X641732D02*
D03*
X638189D02*
D03*
X575919Y-236906D02*
D03*
X596702Y-247441D02*
D03*
X591978D02*
D03*
X586466D02*
D03*
X580954Y-207189D02*
D03*
X580935Y-237412D02*
D03*
X554519Y-212889D02*
D03*
X546419Y-246106D02*
D03*
X626819Y-244005D02*
D03*
X611094Y-248110D02*
D03*
X603002Y-247441D02*
D03*
X531496Y-262647D02*
D03*
X461811Y-310679D02*
D03*
X450000Y-293750D02*
D03*
X422441Y-293789D02*
D03*
X531496Y-213435D02*
D03*
X338525Y-243567D02*
D03*
X525591Y-233088D02*
D03*
X439697Y-162549D02*
D03*
X343144Y-225173D02*
D03*
X420669Y-157923D02*
D03*
X531496Y-223277D02*
D03*
X338583Y-235236D02*
D03*
X525591Y-242962D02*
D03*
X430150Y-162253D02*
D03*
X343444Y-215373D02*
D03*
X432283Y-293750D02*
D03*
X410528Y-157923D02*
D03*
X342944Y-264473D02*
D03*
X444095Y-293750D02*
D03*
X422835Y-311072D02*
D03*
X531496Y-233088D02*
D03*
X430150Y-157923D02*
D03*
X338444Y-225173D02*
D03*
X402756Y-311072D02*
D03*
X525591Y-253969D02*
D03*
X420079Y-162549D02*
D03*
X343403Y-205651D02*
D03*
X525591Y-203592D02*
D03*
X400295Y-157824D02*
D03*
X343144Y-254773D02*
D03*
X431928Y-311189D02*
D03*
X531496Y-242962D02*
D03*
X338844Y-215273D02*
D03*
X402362Y-293750D02*
D03*
X525591Y-262647D02*
D03*
X410913Y-162758D02*
D03*
X338444Y-264473D02*
D03*
X456299Y-293750D02*
D03*
X437795Y-293750D02*
D03*
X525591Y-213435D02*
D03*
X459319Y-162510D02*
D03*
Y-157922D02*
D03*
X342744Y-243747D02*
D03*
X412598Y-311072D02*
D03*
X531496Y-253969D02*
D03*
X449803Y-157923D02*
D03*
X338744Y-205473D02*
D03*
X531496Y-203592D02*
D03*
X401279Y-162509D02*
D03*
X439961Y-157923D02*
D03*
X338444Y-254773D02*
D03*
X461417Y-293750D02*
D03*
X525591Y-223277D02*
D03*
X449508Y-162549D02*
D03*
X343504Y-235236D02*
D03*
X412205Y-293750D02*
D03*
X639750Y-314581D02*
D03*
X658647Y-314581D02*
D03*
X509405Y-345138D02*
D03*
X509011Y-330177D02*
D03*
X56441Y-143600D02*
D03*
Y-151600D02*
D03*
Y-191600D02*
D03*
Y-199600D02*
D03*
Y-215600D02*
D03*
Y-223600D02*
D03*
Y-231600D02*
D03*
Y-247600D02*
D03*
Y-255600D02*
D03*
Y-271600D02*
D03*
Y-279600D02*
D03*
Y-287600D02*
D03*
Y-303600D02*
D03*
Y-311600D02*
D03*
Y-327600D02*
D03*
Y-335600D02*
D03*
Y-343600D02*
D03*
Y-351600D02*
D03*
X54441Y-139600D02*
D03*
X52441Y-143600D02*
D03*
X54441Y-147600D02*
D03*
X52441Y-151600D02*
D03*
Y-191600D02*
D03*
X54441Y-195600D02*
D03*
X52441Y-199600D02*
D03*
X54441Y-203600D02*
D03*
X52441Y-215600D02*
D03*
X54441Y-219600D02*
D03*
X52441Y-223600D02*
D03*
X54441Y-227600D02*
D03*
X52441Y-231600D02*
D03*
X54441Y-235600D02*
D03*
Y-243600D02*
D03*
X52441Y-247600D02*
D03*
X54441Y-251600D02*
D03*
X52441Y-255600D02*
D03*
X54441Y-267600D02*
D03*
X52441Y-271600D02*
D03*
X54441Y-275600D02*
D03*
X52441Y-279600D02*
D03*
Y-287600D02*
D03*
X54441Y-291600D02*
D03*
Y-299600D02*
D03*
X52441Y-303600D02*
D03*
X54441Y-307600D02*
D03*
X52441Y-311600D02*
D03*
X54441Y-323600D02*
D03*
X52441Y-327600D02*
D03*
X54441Y-331600D02*
D03*
X52441Y-335600D02*
D03*
X54441Y-339600D02*
D03*
X52441Y-343600D02*
D03*
Y-351600D02*
D03*
X50441Y-139600D02*
D03*
X48441Y-143600D02*
D03*
X50441Y-195600D02*
D03*
X48441Y-199600D02*
D03*
Y-223600D02*
D03*
X50441Y-227600D02*
D03*
X48441Y-231600D02*
D03*
X50441Y-235600D02*
D03*
Y-243600D02*
D03*
X48441Y-247600D02*
D03*
X50441Y-251600D02*
D03*
Y-275600D02*
D03*
X48441Y-279600D02*
D03*
Y-287600D02*
D03*
X50441Y-291600D02*
D03*
Y-299600D02*
D03*
X48441Y-303600D02*
D03*
X50441Y-331600D02*
D03*
X48441Y-335600D02*
D03*
X50441Y-339600D02*
D03*
X48441Y-343600D02*
D03*
Y-351600D02*
D03*
X46441Y-139600D02*
D03*
X44441Y-143600D02*
D03*
X46441Y-227600D02*
D03*
X44441Y-231600D02*
D03*
X46441Y-235600D02*
D03*
Y-243600D02*
D03*
X44441Y-247600D02*
D03*
Y-279600D02*
D03*
Y-287600D02*
D03*
X46441Y-291600D02*
D03*
Y-299600D02*
D03*
Y-331600D02*
D03*
X44441Y-335600D02*
D03*
X46441Y-339600D02*
D03*
X44441Y-343600D02*
D03*
Y-351600D02*
D03*
X42441Y-139600D02*
D03*
X40441Y-143600D02*
D03*
Y-223600D02*
D03*
X42441Y-227600D02*
D03*
X40441Y-231600D02*
D03*
X42441Y-235600D02*
D03*
Y-243600D02*
D03*
X40441Y-247600D02*
D03*
X42441Y-299600D02*
D03*
Y-331600D02*
D03*
X40441Y-335600D02*
D03*
X42441Y-339600D02*
D03*
X40441Y-343600D02*
D03*
Y-351600D02*
D03*
X38441Y-139600D02*
D03*
X36441Y-143600D02*
D03*
Y-151600D02*
D03*
Y-215600D02*
D03*
Y-223600D02*
D03*
X38441Y-227600D02*
D03*
X36441Y-231600D02*
D03*
X38441Y-235600D02*
D03*
Y-243600D02*
D03*
X36441Y-247600D02*
D03*
X38441Y-251600D02*
D03*
X36441Y-255600D02*
D03*
Y-327600D02*
D03*
X38441Y-331600D02*
D03*
X36441Y-335600D02*
D03*
X38441Y-339600D02*
D03*
X36441Y-343600D02*
D03*
Y-351600D02*
D03*
X34441Y-139600D02*
D03*
X32441Y-143600D02*
D03*
X34441Y-147600D02*
D03*
X32441Y-151600D02*
D03*
X34441Y-163600D02*
D03*
Y-219600D02*
D03*
Y-227600D02*
D03*
Y-235600D02*
D03*
Y-243600D02*
D03*
Y-251600D02*
D03*
Y-267600D02*
D03*
Y-275600D02*
D03*
Y-299600D02*
D03*
Y-307600D02*
D03*
Y-323600D02*
D03*
X32441Y-327600D02*
D03*
X34441Y-331600D02*
D03*
X32441Y-335600D02*
D03*
X34441Y-339600D02*
D03*
X32441Y-343600D02*
D03*
Y-351600D02*
D03*
X30441Y-139600D02*
D03*
X28441Y-143600D02*
D03*
X30441Y-147600D02*
D03*
X28441Y-151600D02*
D03*
X30441Y-163600D02*
D03*
X28441Y-167600D02*
D03*
Y-327600D02*
D03*
X30441Y-331600D02*
D03*
X28441Y-335600D02*
D03*
X30441Y-339600D02*
D03*
X28441Y-343600D02*
D03*
Y-351600D02*
D03*
X26441Y-139600D02*
D03*
X24441Y-143600D02*
D03*
X26441Y-147600D02*
D03*
X24441Y-151600D02*
D03*
X26441Y-163600D02*
D03*
X24441Y-167600D02*
D03*
Y-191600D02*
D03*
X26441Y-195600D02*
D03*
X24441Y-287600D02*
D03*
X26441Y-299600D02*
D03*
X24441Y-303600D02*
D03*
X26441Y-307600D02*
D03*
X24441Y-311600D02*
D03*
X26441Y-331600D02*
D03*
X24441Y-335600D02*
D03*
X26441Y-339600D02*
D03*
X24441Y-343600D02*
D03*
Y-351600D02*
D03*
X22441Y-139600D02*
D03*
X20441Y-143600D02*
D03*
X22441Y-147600D02*
D03*
X20441Y-151600D02*
D03*
X22441Y-163600D02*
D03*
X20441Y-167600D02*
D03*
X22441Y-171600D02*
D03*
X20441Y-191600D02*
D03*
X22441Y-195600D02*
D03*
X20441Y-199600D02*
D03*
Y-231600D02*
D03*
X22441Y-235600D02*
D03*
Y-243600D02*
D03*
X20441Y-247600D02*
D03*
X22441Y-251600D02*
D03*
X20441Y-255600D02*
D03*
X22441Y-259600D02*
D03*
Y-267600D02*
D03*
X20441Y-271600D02*
D03*
X22441Y-283600D02*
D03*
X20441Y-287600D02*
D03*
X22441Y-291600D02*
D03*
Y-299600D02*
D03*
X20441Y-303600D02*
D03*
X22441Y-307600D02*
D03*
X20441Y-311600D02*
D03*
X22441Y-323600D02*
D03*
X20441Y-335600D02*
D03*
X22441Y-339600D02*
D03*
X20441Y-343600D02*
D03*
Y-351600D02*
D03*
X18441Y-139600D02*
D03*
X16441Y-143600D02*
D03*
X18441Y-147600D02*
D03*
X16441Y-151600D02*
D03*
X18441Y-163600D02*
D03*
X16441Y-167600D02*
D03*
X18441Y-171600D02*
D03*
X16441Y-191600D02*
D03*
X18441Y-195600D02*
D03*
X16441Y-199600D02*
D03*
X18441Y-203600D02*
D03*
X16441Y-215600D02*
D03*
X18441Y-219600D02*
D03*
X16441Y-223600D02*
D03*
X18441Y-235600D02*
D03*
Y-243600D02*
D03*
X16441Y-247600D02*
D03*
X18441Y-251600D02*
D03*
X16441Y-255600D02*
D03*
X18441Y-259600D02*
D03*
Y-267600D02*
D03*
X16441Y-271600D02*
D03*
X18441Y-275600D02*
D03*
X16441Y-279600D02*
D03*
X18441Y-291600D02*
D03*
Y-299600D02*
D03*
X16441Y-303600D02*
D03*
X18441Y-307600D02*
D03*
X16441Y-311600D02*
D03*
X18441Y-323600D02*
D03*
X16441Y-327600D02*
D03*
X18441Y-339600D02*
D03*
X16441Y-343600D02*
D03*
Y-351600D02*
D03*
X14441Y-139600D02*
D03*
X12441Y-143600D02*
D03*
X14441Y-147600D02*
D03*
X12441Y-151600D02*
D03*
X14441Y-163600D02*
D03*
X12441Y-167600D02*
D03*
X14441Y-171600D02*
D03*
X12441Y-191600D02*
D03*
X14441Y-195600D02*
D03*
X12441Y-199600D02*
D03*
X14441Y-203600D02*
D03*
X12441Y-215600D02*
D03*
X14441Y-219600D02*
D03*
X12441Y-223600D02*
D03*
X14441Y-243600D02*
D03*
X12441Y-247600D02*
D03*
X14441Y-251600D02*
D03*
X12441Y-255600D02*
D03*
X14441Y-259600D02*
D03*
Y-267600D02*
D03*
X12441Y-271600D02*
D03*
X14441Y-275600D02*
D03*
X12441Y-279600D02*
D03*
X14441Y-291600D02*
D03*
Y-299600D02*
D03*
X12441Y-303600D02*
D03*
X14441Y-307600D02*
D03*
X12441Y-311600D02*
D03*
X14441Y-323600D02*
D03*
X12441Y-327600D02*
D03*
X14441Y-331600D02*
D03*
X12441Y-343600D02*
D03*
Y-351600D02*
D03*
X10441Y-139600D02*
D03*
Y-163600D02*
D03*
Y-171600D02*
D03*
X8441Y-191600D02*
D03*
X10441Y-195600D02*
D03*
Y-203600D02*
D03*
Y-227600D02*
D03*
Y-243600D02*
D03*
X8441Y-247600D02*
D03*
X10441Y-251600D02*
D03*
Y-259600D02*
D03*
Y-267600D02*
D03*
Y-275600D02*
D03*
X8441Y-279600D02*
D03*
X10441Y-299600D02*
D03*
Y-323600D02*
D03*
Y-331600D02*
D03*
X8441Y-351600D02*
D03*
X6441Y-139600D02*
D03*
X4441Y-191600D02*
D03*
X6441Y-243600D02*
D03*
X4441Y-351600D02*
D03*
X2441Y-243600D02*
D03*
X441Y-351600D02*
D03*
X-3559Y-191600D02*
D03*
X-1559Y-243600D02*
D03*
X-3559Y-351600D02*
D03*
X-5559Y-139600D02*
D03*
X-7559Y-143600D02*
D03*
Y-167600D02*
D03*
Y-191600D02*
D03*
Y-199600D02*
D03*
Y-223600D02*
D03*
X-5559Y-227600D02*
D03*
Y-243600D02*
D03*
X-7559Y-247600D02*
D03*
Y-279600D02*
D03*
X-5559Y-299600D02*
D03*
X-7559Y-303600D02*
D03*
Y-327600D02*
D03*
Y-351600D02*
D03*
X-9559Y-139600D02*
D03*
Y-171600D02*
D03*
X-11559Y-191600D02*
D03*
X-9559Y-195600D02*
D03*
Y-227600D02*
D03*
Y-243600D02*
D03*
X-11559Y-247600D02*
D03*
X-9559Y-251600D02*
D03*
Y-275600D02*
D03*
X-11559Y-279600D02*
D03*
X-9559Y-299600D02*
D03*
Y-331600D02*
D03*
X-11559Y-351600D02*
D03*
X-13559Y-139600D02*
D03*
X-15559Y-191600D02*
D03*
X-13559Y-243600D02*
D03*
X-15559Y-351600D02*
D03*
X-19559Y-263600D02*
D03*
Y-351600D02*
D03*
X-23559Y-159600D02*
D03*
Y-191600D02*
D03*
X-21559Y-211600D02*
D03*
X-23559Y-263600D02*
D03*
X-21559Y-315600D02*
D03*
X-23559Y-351600D02*
D03*
X-25559Y-139600D02*
D03*
Y-155600D02*
D03*
Y-211600D02*
D03*
Y-259600D02*
D03*
Y-267600D02*
D03*
Y-299600D02*
D03*
Y-315600D02*
D03*
X269685Y-136843D02*
D03*
X234252Y-133742D02*
D03*
X263779Y-106151D02*
D03*
X71850Y-147638D02*
D03*
X75787Y-131890D02*
D03*
X643701Y-63976D02*
D03*
X644685Y-45276D02*
D03*
X623000Y-37402D02*
D03*
X610236Y-8858D02*
D03*
X609252Y-26575D02*
D03*
X98425Y-102362D02*
D03*
X89567D02*
D03*
X85630Y-313976D02*
D03*
X86614Y-258858D02*
D03*
X81693Y-205709D02*
D03*
X86614Y-110236D02*
D03*
X63976Y-227362D02*
D03*
X68898Y-285433D02*
D03*
X67913Y-340551D02*
D03*
X68573Y-179321D02*
D03*
X44291Y-252953D02*
D03*
Y-272638D02*
D03*
Y-326772D02*
D03*
Y-307087D02*
D03*
X26575Y-291339D02*
D03*
X31496Y-189961D02*
D03*
X44291Y-147638D02*
D03*
Y-167323D02*
D03*
Y-200787D02*
D03*
Y-220472D02*
D03*
X570727Y-105662D02*
D03*
X103409Y-141732D02*
D03*
X103347Y-110236D02*
D03*
X119095Y-126047D02*
D03*
X494095Y-137647D02*
D03*
X518701Y-104214D02*
D03*
X519587Y-134596D02*
D03*
X528543Y-104214D02*
D03*
X114173Y-83088D02*
D03*
X441929Y-122883D02*
D03*
X256890Y-124852D02*
D03*
Y-121899D02*
D03*
X250000Y-120915D02*
D03*
X129921Y-79576D02*
D03*
X473425Y-125836D02*
D03*
X473425Y-123868D02*
D03*
X473425Y-121899D02*
D03*
X505905Y-137647D02*
D03*
X163071Y-390730D02*
D03*
X632432Y-132480D02*
D03*
X614321Y-118307D02*
D03*
X99410Y-50049D02*
D03*
X632432Y-141142D02*
D03*
X259285Y-390247D02*
D03*
X267204Y-390009D02*
D03*
X216162Y-390947D02*
D03*
X235144Y-390416D02*
D03*
X251456Y-390009D02*
D03*
X226063Y-390722D02*
D03*
X281201Y-390009D02*
D03*
X174941Y-390600D02*
D03*
X202441D02*
D03*
X538813Y-144506D02*
D03*
X544813Y-109806D02*
D03*
X566813Y-132405D02*
D03*
D171*
X99016Y-121653D02*
D03*
X103347D02*
D03*
X107677D02*
D03*
X99016Y-125984D02*
D03*
X103347D02*
D03*
X107677D02*
D03*
X99016Y-130315D02*
D03*
X103347D02*
D03*
X107677D02*
D03*
M02*
